G04 ================== begin FILE IDENTIFICATION RECORD ==================*
G04 Layout Name:  D:/<user>/Wistron_project/16347-sc/gbr/16347-sc.brd*
G04 Film Name:    DRILL*
G04 File Format:  Gerber RS274X*
G04 File Origin:  Cadence Allegro 16.5-S056*
G04 Origin Date:  Tue Mar 14 17:08:18 2017*
G04 *
G04 Layer:  MANUFACTURING/NCLEGEND-1-2*
G04 Layer:  MANUFACTURING/DRILL SIZE*
G04 Layer:  DRAWING FORMAT/LAYER_PCB_STORY*
G04 Layer:  DRAWING FORMAT/LAYER_DRILL*
G04 Layer:  BOARD GEOMETRY/PANEL_OUTLINE*
G04 *
G04 Offset:    (0.00 0.00)*
G04 Mirror:    No*
G04 Mode:      Positive*
G04 Rotation:  0*
G04 FullContactRelief:  No*
G04 UndefLineWidth:     6.00*
G04 ================== end FILE IDENTIFICATION RECORD ====================*
%FSLAX35Y35*MOIN*%
%IR0*IPPOS*OFA0.00000B0.00000*MIA0B0*SFA1.00000B1.00000*%
%AMMACRO11*
1,1,.006,.0505,.0505*
20,1,.006,.0505,.0505,.0505,-.0505,0.0*
1,1,.006,.0505,-.0505*
20,1,.006,.0505,-.0505,-.0505,-.0505,0.0*
1,1,.006,-.0505,-.0505*
20,1,.006,-.0505,-.0505,-.0505,.0505,0.0*
1,1,.006,-.0505,.0505*
20,1,.006,-.0505,.0505,.0505,.0505,0.0*
1,1,.006,.0505,.0505*
1,1,.006,-.01599,.01683*
20,1,.006,-.01599,.01683,-.01094,.02188,0.0*
1,1,.006,-.01094,.02188*
20,1,.006,-.01094,.02188,-.00505,.02441,0.0*
1,1,.006,-.00505,.02441*
20,1,.006,-.00505,.02441,.00168,.02525,0.0*
1,1,.006,.00168,.02525*
20,1,.006,.00168,.02525,.0101,.02357,0.0*
1,1,.006,.0101,.02357*
20,1,.006,.0101,.02357,.01599,.01936,0.0*
1,1,.006,.01599,.01936*
20,1,.006,.01599,.01936,.01768,.01431,0.0*
1,1,.006,.01768,.01431*
20,1,.006,.01768,.01431,.01683,.00926,0.0*
1,1,.006,.01683,.00926*
20,1,.006,.01683,.00926,.01347,.00505,0.0*
1,1,.006,.01347,.00505*
20,1,.006,.01347,.00505,-.00337,-.00337,0.0*
1,1,.006,-.00337,-.00337*
20,1,.006,-.00337,-.00337,-.01094,-.00926,0.0*
1,1,.006,-.01094,-.00926*
20,1,.006,-.01094,-.00926,-.01599,-.01768,0.0*
1,1,.006,-.01599,-.01768*
20,1,.006,-.01599,-.01768,-.01768,-.02525,0.0*
1,1,.006,-.01768,-.02525*
20,1,.006,-.01768,-.02525,.01768,-.02525,0.0*
1,1,.006,.01768,-.02525*
%
%ADD11MACRO11*%
%AMMACRO13*
1,1,.006,.006,0.0*
20,1,.006,.006,0.0,-.006,0.0,0.0*
1,1,.006,-.006,0.0*
1,1,.006,0.0,.006*
20,1,.006,0.0,.006,0.0,-.006,0.0*
1,1,.006,0.0,-.006*
1,1,.006,.003,0.0*
20,1,.006,.003,0.0,.003,.006,0.0*
1,1,.006,.003,.006*
20,1,.006,.003,.006,.0018,.0048,0.0*
1,1,.006,.0018,.0048*
1,1,.006,.0018,0.0*
20,1,.006,.0018,0.0,.0042,0.0,0.0*
1,1,.006,.0042,0.0*
%
%ADD13MACRO13*%
%AMMACRO12*
1,1,.006,0.0,.0575*
20,1,.006,0.0,.0575,-.049796,.02875,0.0*
1,1,.006,-.049796,.02875*
20,1,.006,-.049796,.02875,-.049796,-.02875,0.0*
1,1,.006,-.049796,-.02875*
20,1,.006,-.049796,-.02875,0.0,-.0575,0.0*
1,1,.006,0.0,-.0575*
20,1,.006,0.0,-.0575,.049796,-.02875,0.0*
1,1,.006,.049796,-.02875*
20,1,.006,.049796,-.02875,.049796,.02875,0.0*
1,1,.006,.049796,.02875*
20,1,.006,.049796,.02875,0.0,.0575,0.0*
1,1,.006,0.0,.0575*
1,1,.006,.0115,-.02875*
20,1,.006,.0115,-.02875,.0115,.02875,0.0*
1,1,.006,.0115,.02875*
20,1,.006,.0115,.02875,-.02396,-.01246,0.0*
1,1,.006,-.02396,-.01246*
20,1,.006,-.02396,-.01246,.02396,-.01246,0.0*
1,1,.006,.02396,-.01246*
%
%ADD12MACRO12*%
%AMMACRO10*
1,1,.006,.043,0.0*
20,1,.006,.043,0.0,.0215,.037239,0.0*
1,1,.006,.0215,.037239*
20,1,.006,.0215,.037239,-.0215,.037239,0.0*
1,1,.006,-.0215,.037239*
20,1,.006,-.0215,.037239,-.043,0.0,0.0*
1,1,.006,-.043,0.0*
20,1,.006,-.043,0.0,-.0215,-.037239,0.0*
1,1,.006,-.0215,-.037239*
20,1,.006,-.0215,-.037239,.0215,-.037239,0.0*
1,1,.006,.0215,-.037239*
20,1,.006,.0215,-.037239,.043,0.0,0.0*
1,1,.006,.043,0.0*
1,1,.006,-.01577,-.0129*
20,1,.006,-.01577,-.0129,-.01147,-.01792,0.0*
1,1,.006,-.01147,-.01792*
20,1,.006,-.01147,-.01792,-.00573,-.02078,0.0*
1,1,.006,-.00573,-.02078*
20,1,.006,-.00573,-.02078,.00072,-.0215,0.0*
1,1,.006,.00072,-.0215*
20,1,.006,.00072,-.0215,.00645,-.02078,0.0*
1,1,.006,.00645,-.02078*
20,1,.006,.00645,-.02078,.01218,-.0172,0.0*
1,1,.006,.01218,-.0172*
20,1,.006,.01218,-.0172,.01577,-.0129,0.0*
1,1,.006,.01577,-.0129*
20,1,.006,.01577,-.0129,.01648,-.0086,0.0*
1,1,.006,.01648,-.0086*
20,1,.006,.01648,-.0086,.01505,-.00358,0.0*
1,1,.006,.01505,-.00358*
20,1,.006,.01505,-.00358,.01003,0.0,0.0*
1,1,.006,.01003,0.0*
20,1,.006,.01003,0.0,.00502,.00143,0.0*
1,1,.006,.00502,.00143*
20,1,.006,.00502,.00143,-.00143,.00143,0.0*
1,1,.006,-.00143,.00143*
1,1,.006,.00502,.00143*
20,1,.006,.00502,.00143,.00932,.00358,0.0*
1,1,.006,.00932,.00358*
20,1,.006,.00932,.00358,.0129,.00717,0.0*
1,1,.006,.0129,.00717*
20,1,.006,.0129,.00717,.01433,.01147,0.0*
1,1,.006,.01433,.01147*
20,1,.006,.01433,.01147,.0129,.01577,0.0*
1,1,.006,.0129,.01577*
20,1,.006,.0129,.01577,.00932,.01935,0.0*
1,1,.006,.00932,.01935*
20,1,.006,.00932,.01935,.00287,.0215,0.0*
1,1,.006,.00287,.0215*
20,1,.006,.00287,.0215,-.00358,.02078,0.0*
1,1,.006,-.00358,.02078*
20,1,.006,-.00358,.02078,-.01003,.01792,0.0*
1,1,.006,-.01003,.01792*
%
%ADD10MACRO10*%
%ADD14C,.02*%
%ADD15C,.006*%
G75*
%LPD*%
G75*
G54D10*
X35185Y15572D03*
X16240Y99213D03*
Y233859D03*
Y368505D03*
Y503151D03*
Y637797D03*
Y772443D03*
Y907089D03*
X693024Y26550D03*
X784745Y19685D03*
Y154331D03*
Y288977D03*
Y423623D03*
Y558269D03*
Y692915D03*
Y827561D03*
X962150Y344350D03*
G54D11*
X16240Y19684D03*
X301968Y19685D03*
X488681Y19684D03*
X712106D03*
X962150Y372450D03*
G54D12*
X47737Y19685D03*
X680610D03*
X962150Y316250D03*
G54D13*
X38675Y22425D03*
X20459Y5682D03*
X35539Y4546D03*
X4758Y4649D03*
X41942Y46869D03*
X42071Y58644D03*
X5223Y34706D03*
X30374Y34551D03*
X90368Y245D03*
X63477Y4598D03*
X71000Y11600D03*
X84600Y12000D03*
X59871Y19900D03*
X59100Y56200D03*
X55513Y51513D03*
X47800Y56500D03*
X51573Y51573D03*
X76200Y35200D03*
X65000Y45100D03*
X65100Y59000D03*
X54026Y28870D03*
X46376Y36160D03*
X113912Y245D03*
X124500Y12100D03*
X111100Y10400D03*
X100000Y16500D03*
X135500Y29976D03*
X126106Y29996D03*
X102586Y30227D03*
X112024Y30080D03*
X99000Y35000D03*
X145601Y245D03*
X179537Y9829D03*
X174542Y4205D03*
X140900Y23800D03*
X139300Y19000D03*
X162191Y24351D03*
X165593Y21701D03*
X175800Y67500D03*
X164200Y62000D03*
X164378Y52020D03*
X145200Y26300D03*
X225477Y20626D03*
X189652Y8444D03*
X202034Y4247D03*
X233765Y34883D03*
X219878Y32075D03*
X217446Y46840D03*
Y51035D03*
X222700Y60100D03*
X216500Y67500D03*
X197800D03*
X199700Y63910D03*
X195500D03*
X191500D03*
X249762Y12946D03*
X265042Y13093D03*
X238391Y14434D03*
X241359Y21413D03*
X238755Y26619D03*
X279170Y35245D03*
X256656Y35189D03*
X245853Y31620D03*
X323200Y13800D03*
X283197Y20870D03*
X307599Y54564D03*
X302200Y51718D03*
X296005Y55029D03*
X304088Y48291D03*
X290350Y46275D03*
X290660Y58851D03*
X316800Y35900D03*
X313200Y45500D03*
X313500Y58100D03*
X348900Y13700D03*
X330300Y26000D03*
X365800Y26400D03*
X339400Y34800D03*
X404600Y14400D03*
X383600Y14000D03*
X414700Y13800D03*
X405000Y20700D03*
X420635Y54538D03*
X424211Y52000D03*
X394400Y26300D03*
X402400Y34800D03*
X414600Y44600D03*
X414700Y58000D03*
X384600Y34800D03*
X455689Y15598D03*
X446135Y10537D03*
X428600Y13800D03*
X447000Y20700D03*
X431894Y54627D03*
X428151Y52151D03*
X436012Y59651D03*
X437768Y51052D03*
X438311Y39148D03*
X448019Y35172D03*
X462893D03*
X455817Y26237D03*
X516716Y15930D03*
X501900Y10348D03*
X473919Y10744D03*
X518856Y25583D03*
X503159Y35111D03*
X473300Y25875D03*
X563034Y312D03*
X532070Y10129D03*
X541225Y13900D03*
X554500Y13000D03*
X531500Y20300D03*
X555996Y54409D03*
X552364Y52136D03*
X544789Y54552D03*
X548424Y52000D03*
X565606Y36026D03*
X561619Y47946D03*
X561954Y58858D03*
X538954Y59320D03*
X538911Y42406D03*
X529979Y35111D03*
X601510Y277D03*
X614586Y25544D03*
X580014Y25376D03*
X580128Y14830D03*
X574168Y7737D03*
X573300Y20500D03*
X615510Y35060D03*
X581051Y35186D03*
X646777Y311D03*
X628333Y278D03*
X662275Y4597D03*
X625457Y14410D03*
X617398Y7695D03*
X632900Y13300D03*
X647600Y12500D03*
X623300Y19600D03*
X644052Y35251D03*
X663106Y43749D03*
X663022Y59320D03*
X695912Y18399D03*
X671342Y13872D03*
X704646Y4135D03*
X684016Y4178D03*
X665500Y19700D03*
X680189Y54619D03*
X676576Y52380D03*
X668373Y54326D03*
X672636Y52380D03*
X685686Y59530D03*
X686484Y39279D03*
X701971Y35249D03*
X670753Y27514D03*
X724174Y4463D03*
X723902Y35018D03*
X962150Y400550D03*
G54D14*
G01X-23515Y-108314D02*
X-55515D01*
G01X-23515Y-124314D02*
Y-204314D01*
G01D02*
X1177585D01*
G01X-27515Y-108314D02*
G02I-12000J0D01*
G01X-39515Y-124314D02*
Y-92314D01*
G01X-23515Y-124314D02*
X1177585D01*
G01X-23515Y-159814D02*
X1177585D01*
G01X-32665Y-108314D02*
G02I-6850J0D01*
G01X390085Y-124314D02*
Y-204314D01*
G01X527585Y-124314D02*
Y-204314D01*
G01X642585Y-124314D02*
Y-204314D01*
G01X810085Y-124314D02*
Y-204314D01*
G01X980085Y-124314D02*
Y-204314D01*
G01X1177585Y-124314D02*
Y-204314D01*
G01X1205585Y-108314D02*
G02I-12000J0D01*
G01X1200435D02*
G02I-6850J0D01*
G01X1209585D02*
X1177585D01*
G01X1193585Y-124314D02*
Y-92314D01*
G54D15*
G01X981Y-184981D02*
X1855Y-184106D01*
X2510Y-182648D01*
X2947Y-180605D01*
X2510Y-178856D01*
X1637Y-177689D01*
X108Y-176814D01*
X-5787D01*
Y-194314D01*
X1418D01*
X2947Y-193148D01*
X3820Y-191397D01*
X4257Y-189356D01*
X3820Y-187314D01*
X2510Y-185564D01*
X981Y-184981D01*
X-5787D01*
G01X13678Y-194314D02*
Y-182648D01*
G01Y-184981D02*
X14770Y-183814D01*
X15862Y-182939D01*
X17390Y-182648D01*
X18481Y-182939D01*
X19792Y-183814D01*
G01X29650Y-199564D02*
X30960Y-200147D01*
X32707Y-199564D01*
X33798Y-198398D01*
X34672Y-196939D01*
X35981Y-192273D01*
X38820Y-182648D01*
G01X31833D02*
X35981Y-192273D01*
G01X55228Y-184106D02*
X53700Y-182939D01*
X52390Y-182648D01*
X50643Y-183231D01*
X49333Y-184397D01*
X48460Y-186439D01*
X48241Y-188481D01*
X48460Y-190523D01*
X49333Y-192273D01*
X50643Y-193731D01*
X52390Y-194314D01*
X53918Y-193731D01*
X55228Y-192564D01*
G01X65960Y-186439D02*
X72947D01*
X72292Y-184397D01*
X71200Y-183231D01*
X69672Y-182648D01*
X68143Y-182939D01*
X66833Y-183814D01*
X65960Y-185856D01*
X65523Y-187606D01*
Y-189356D01*
X65960Y-191106D01*
X67052Y-192856D01*
X68362Y-194022D01*
X69890Y-194314D01*
X71418Y-193731D01*
X72947Y-191981D01*
G01X109038Y-178273D02*
X107728Y-177397D01*
X106200Y-176814D01*
X104453D01*
X102488Y-177689D01*
X100960Y-179147D01*
X99868Y-180898D01*
X98995Y-183814D01*
X98776Y-186439D01*
X99213Y-189064D01*
X99868Y-190814D01*
X101178Y-192564D01*
X102707Y-193731D01*
X104235Y-194314D01*
X105763D01*
X107292Y-193731D01*
X108602Y-192856D01*
X109694Y-191690D01*
G01X125665Y-194314D02*
Y-182648D01*
G01Y-184689D02*
X124792Y-183523D01*
X123481Y-182939D01*
X121953Y-182648D01*
X120425Y-183231D01*
X119115Y-184397D01*
X118241Y-186147D01*
X117805Y-188481D01*
X118241Y-190814D01*
X119115Y-192564D01*
X120425Y-193731D01*
X121953Y-194314D01*
X123481Y-194022D01*
X124792Y-193148D01*
X125665Y-191981D01*
G01X135523Y-194314D02*
Y-182648D01*
G01Y-185564D02*
X136397Y-184106D01*
X137707Y-182939D01*
X139453Y-182648D01*
X140981Y-182939D01*
X142292Y-184106D01*
X142947Y-186147D01*
Y-194314D01*
G01X152150Y-199564D02*
X153460Y-200147D01*
X155207Y-199564D01*
X156298Y-198398D01*
X157172Y-196939D01*
X158481Y-192273D01*
X161320Y-182648D01*
G01X154333D02*
X158481Y-192273D01*
G01X174235Y-194314D02*
X172925Y-194022D01*
X171615Y-192856D01*
X170741Y-190814D01*
X170305Y-188481D01*
X170741Y-186147D01*
X171615Y-184106D01*
X172925Y-182939D01*
X174235Y-182648D01*
X175545Y-182939D01*
X176855Y-184106D01*
X177728Y-186147D01*
X177947Y-188481D01*
X177728Y-190814D01*
X176855Y-192856D01*
X175545Y-194022D01*
X174235Y-194314D01*
G01X188023D02*
Y-182648D01*
G01Y-185564D02*
X188897Y-184106D01*
X190207Y-182939D01*
X191953Y-182648D01*
X193481Y-182939D01*
X194792Y-184106D01*
X195447Y-186147D01*
Y-194314D01*
G01X222368Y-176814D02*
Y-194314D01*
X231102D01*
G01X248602D02*
X239868D01*
Y-176814D01*
X248602D01*
G01X245108Y-185272D02*
X239868D01*
G01X256932Y-194314D02*
Y-176814D01*
X261298D01*
X263045Y-177689D01*
X264355Y-178856D01*
X265447Y-180605D01*
X266320Y-182648D01*
X266538Y-185564D01*
X266320Y-188481D01*
X265447Y-190523D01*
X264355Y-192273D01*
X263045Y-193439D01*
X261298Y-194314D01*
X256932D01*
G01X298481Y-184981D02*
X299355Y-184106D01*
X300010Y-182648D01*
X300447Y-180605D01*
X300010Y-178856D01*
X299137Y-177689D01*
X297608Y-176814D01*
X291713D01*
Y-194314D01*
X298918D01*
X300447Y-193148D01*
X301320Y-191397D01*
X301757Y-189356D01*
X301320Y-187314D01*
X300010Y-185564D01*
X298481Y-184981D01*
X291713D01*
G01X314235Y-194314D02*
X312925Y-194022D01*
X311615Y-192856D01*
X310741Y-190814D01*
X310305Y-188481D01*
X310741Y-186147D01*
X311615Y-184106D01*
X312925Y-182939D01*
X314235Y-182648D01*
X315545Y-182939D01*
X316855Y-184106D01*
X317728Y-186147D01*
X317947Y-188481D01*
X317728Y-190814D01*
X316855Y-192856D01*
X315545Y-194022D01*
X314235Y-194314D01*
G01X335665D02*
Y-182648D01*
G01Y-184689D02*
X334792Y-183523D01*
X333481Y-182939D01*
X331953Y-182648D01*
X330425Y-183231D01*
X329115Y-184397D01*
X328241Y-186147D01*
X327805Y-188481D01*
X328241Y-190814D01*
X329115Y-192564D01*
X330425Y-193731D01*
X331953Y-194314D01*
X333481Y-194022D01*
X334792Y-193148D01*
X335665Y-191981D01*
G01X346178Y-194314D02*
Y-182648D01*
G01Y-184981D02*
X347270Y-183814D01*
X348362Y-182939D01*
X349890Y-182648D01*
X350981Y-182939D01*
X352292Y-183814D01*
G01X370665Y-176814D02*
Y-194314D01*
G01Y-191690D02*
X369792Y-193148D01*
X368481Y-194022D01*
X366953Y-194314D01*
X365207Y-193731D01*
X363897Y-192273D01*
X363023Y-190523D01*
X362805Y-188481D01*
X363023Y-186439D01*
X363897Y-184689D01*
X365207Y-183231D01*
X366953Y-182648D01*
X368481Y-182939D01*
X369573Y-183523D01*
X370665Y-184689D01*
G01X142308Y-149314D02*
Y-131814D01*
X147985Y-146397D01*
X153662Y-131814D01*
Y-149314D01*
G01X165485D02*
X164175Y-149022D01*
X162865Y-147856D01*
X161991Y-145814D01*
X161555Y-143481D01*
X161991Y-141147D01*
X162865Y-139106D01*
X164175Y-137939D01*
X165485Y-137648D01*
X166795Y-137939D01*
X168105Y-139106D01*
X168978Y-141147D01*
X169197Y-143481D01*
X168978Y-145814D01*
X168105Y-147856D01*
X166795Y-149022D01*
X165485Y-149314D01*
G01X186915Y-131814D02*
Y-149314D01*
G01Y-146690D02*
X186042Y-148148D01*
X184731Y-149022D01*
X183203Y-149314D01*
X181457Y-148731D01*
X180147Y-147273D01*
X179273Y-145523D01*
X179055Y-143481D01*
X179273Y-141439D01*
X180147Y-139689D01*
X181457Y-138231D01*
X183203Y-137648D01*
X184731Y-137939D01*
X185823Y-138523D01*
X186915Y-139689D01*
G01X197210Y-141439D02*
X204197D01*
X203542Y-139397D01*
X202450Y-138231D01*
X200922Y-137648D01*
X199393Y-137939D01*
X198083Y-138814D01*
X197210Y-140856D01*
X196773Y-142606D01*
Y-144356D01*
X197210Y-146106D01*
X198302Y-147856D01*
X199612Y-149022D01*
X201140Y-149314D01*
X202668Y-148731D01*
X204197Y-146981D01*
G01X217985Y-149314D02*
Y-131814D01*
G01X423785Y-194314D02*
Y-176814D01*
X421165Y-180314D01*
G01Y-194314D02*
X426405D01*
G01X437137Y-187023D02*
X438665Y-184981D01*
X439975Y-183814D01*
X441722Y-183231D01*
X443250Y-183814D01*
X444342Y-184981D01*
X445215Y-186731D01*
X445433Y-188772D01*
X445215Y-190523D01*
X444342Y-192273D01*
X443031Y-193731D01*
X441503Y-194314D01*
X439757Y-193731D01*
X438228Y-191981D01*
X437355Y-189356D01*
X437137Y-186439D01*
X437573Y-182648D01*
X438228Y-180605D01*
X439320Y-178564D01*
X440848Y-177106D01*
X442377Y-176814D01*
X443905Y-177397D01*
X444997Y-178856D01*
G01X453982Y-190814D02*
X455291Y-192856D01*
X457038Y-194022D01*
X459003Y-194314D01*
X460750Y-194022D01*
X462497Y-192564D01*
X463588Y-190814D01*
X463807Y-189064D01*
X463370Y-187023D01*
X461842Y-185564D01*
X460313Y-184981D01*
X458348D01*
G01X460313D02*
X461623Y-184106D01*
X462715Y-182648D01*
X463152Y-180898D01*
X462715Y-179147D01*
X461623Y-177689D01*
X459658Y-176814D01*
X457693Y-177106D01*
X455728Y-178273D01*
G01X478905Y-194314D02*
Y-176814D01*
X470826Y-189356D01*
X481744D01*
G01X493348Y-194314D02*
X493785Y-190523D01*
X494440Y-187314D01*
X495313Y-184397D01*
X496405Y-181189D01*
X498152Y-176814D01*
X489418D01*
G01X410668Y-149314D02*
Y-131814D01*
X415908D01*
X417655Y-132689D01*
X418965Y-134731D01*
X419402Y-137064D01*
X418965Y-139397D01*
X417873Y-141147D01*
X415908Y-142023D01*
X410668D01*
G01X437338Y-133273D02*
X436028Y-132397D01*
X434500Y-131814D01*
X432753D01*
X430788Y-132689D01*
X429260Y-134147D01*
X428168Y-135898D01*
X427295Y-138814D01*
X427076Y-141439D01*
X427513Y-144064D01*
X428168Y-145814D01*
X429478Y-147564D01*
X431007Y-148731D01*
X432535Y-149314D01*
X434063D01*
X435592Y-148731D01*
X436902Y-147856D01*
X437994Y-146690D01*
G01X451781Y-139981D02*
X452655Y-139106D01*
X453310Y-137648D01*
X453747Y-135605D01*
X453310Y-133856D01*
X452437Y-132689D01*
X450908Y-131814D01*
X445013D01*
Y-149314D01*
X452218D01*
X453747Y-148148D01*
X454620Y-146397D01*
X455057Y-144356D01*
X454620Y-142314D01*
X453310Y-140564D01*
X451781Y-139981D01*
X445013D01*
G01X460985Y-155147D02*
X474085D01*
G01X480013Y-149314D02*
Y-131814D01*
X490057Y-149314D01*
Y-131814D01*
G01X502535Y-149314D02*
X500788Y-149022D01*
X499260Y-147856D01*
X497950Y-146106D01*
X497076Y-144064D01*
X496640Y-141731D01*
Y-139397D01*
X497076Y-137064D01*
X497950Y-135022D01*
X499260Y-133273D01*
X500788Y-132106D01*
X502535Y-131814D01*
X504281Y-132106D01*
X505810Y-133273D01*
X507120Y-135022D01*
X507994Y-137064D01*
X508430Y-139397D01*
Y-141731D01*
X507994Y-144064D01*
X507120Y-146106D01*
X505810Y-147856D01*
X504281Y-149022D01*
X502535Y-149314D01*
G01X553376Y-131814D02*
X558835Y-149314D01*
X564294Y-131814D01*
G01X580702Y-149314D02*
X571968D01*
Y-131814D01*
X580702D01*
G01X577208Y-140272D02*
X571968D01*
G01X589468Y-149314D02*
Y-131814D01*
X594927D01*
X596673Y-132689D01*
X597765Y-133856D01*
X598202Y-136189D01*
X597765Y-138523D01*
X596455Y-139981D01*
X594927Y-140856D01*
X589468D01*
G01X594927D02*
X598202Y-149314D01*
G01X611335Y-149897D02*
X610898Y-149606D01*
Y-149022D01*
X611335Y-148731D01*
X611772Y-149022D01*
Y-149606D01*
X611335Y-149897D01*
G01X571750Y-191981D02*
X573497Y-193439D01*
X575462Y-194314D01*
X577208D01*
X578955Y-193439D01*
X580265Y-191981D01*
X580920Y-189939D01*
X580483Y-187898D01*
X579392Y-186147D01*
X577427Y-184981D01*
X574807Y-184397D01*
X573278Y-183231D01*
X572623Y-181189D01*
X573060Y-179147D01*
X574152Y-177689D01*
X575680Y-176814D01*
X577208D01*
X578737Y-177397D01*
X580047Y-178856D01*
G01X598638Y-178273D02*
X597328Y-177397D01*
X595800Y-176814D01*
X594053D01*
X592088Y-177689D01*
X590560Y-179147D01*
X589468Y-180898D01*
X588595Y-183814D01*
X588376Y-186439D01*
X588813Y-189064D01*
X589468Y-190814D01*
X590778Y-192564D01*
X592307Y-193731D01*
X593835Y-194314D01*
X595363D01*
X596892Y-193731D01*
X598202Y-192856D01*
X599294Y-191690D01*
G01X686482Y-194314D02*
Y-176814D01*
X690848D01*
X692595Y-177689D01*
X693905Y-178856D01*
X694997Y-180605D01*
X695870Y-182648D01*
X696088Y-185564D01*
X695870Y-188481D01*
X694997Y-190523D01*
X693905Y-192273D01*
X692595Y-193439D01*
X690848Y-194314D01*
X686482D01*
G01X704418D02*
Y-176814D01*
X709877D01*
X711623Y-177689D01*
X712715Y-178856D01*
X713152Y-181189D01*
X712715Y-183523D01*
X711405Y-184981D01*
X709877Y-185856D01*
X704418D01*
G01X709877D02*
X713152Y-194314D01*
G01X723665Y-176814D02*
X728905D01*
G01X726285D02*
Y-194314D01*
G01X723665D02*
X728905D01*
G01X739418Y-176814D02*
Y-194314D01*
X748152D01*
G01X756918Y-176814D02*
Y-194314D01*
X765652D01*
G01X686918Y-131814D02*
Y-149314D01*
X695652D01*
G01X712715D02*
Y-137648D01*
G01Y-139689D02*
X711842Y-138523D01*
X710531Y-137939D01*
X709003Y-137648D01*
X707475Y-138231D01*
X706165Y-139397D01*
X705291Y-141147D01*
X704855Y-143481D01*
X705291Y-145814D01*
X706165Y-147564D01*
X707475Y-148731D01*
X709003Y-149314D01*
X710531Y-149022D01*
X711842Y-148148D01*
X712715Y-146981D01*
G01X721700Y-154564D02*
X723010Y-155147D01*
X724757Y-154564D01*
X725848Y-153398D01*
X726722Y-151939D01*
X728031Y-147273D01*
X730870Y-137648D01*
G01X723883D02*
X728031Y-147273D01*
G01X740510Y-141439D02*
X747497D01*
X746842Y-139397D01*
X745750Y-138231D01*
X744222Y-137648D01*
X742693Y-137939D01*
X741383Y-138814D01*
X740510Y-140856D01*
X740073Y-142606D01*
Y-144356D01*
X740510Y-146106D01*
X741602Y-147856D01*
X742912Y-149022D01*
X744440Y-149314D01*
X745968Y-148731D01*
X747497Y-146981D01*
G01X758228Y-149314D02*
Y-137648D01*
G01Y-139981D02*
X759320Y-138814D01*
X760412Y-137939D01*
X761940Y-137648D01*
X763031Y-137939D01*
X764342Y-138814D01*
G01X851335Y-194314D02*
X849588Y-194022D01*
X848060Y-192856D01*
X846750Y-191106D01*
X845876Y-189064D01*
X845440Y-186731D01*
Y-184397D01*
X845876Y-182064D01*
X846750Y-180022D01*
X848060Y-178273D01*
X849588Y-177106D01*
X851335Y-176814D01*
X853081Y-177106D01*
X854610Y-178273D01*
X855920Y-180022D01*
X856794Y-182064D01*
X857230Y-184397D01*
Y-186731D01*
X856794Y-189064D01*
X855920Y-191106D01*
X854610Y-192856D01*
X853081Y-194022D01*
X851335Y-194314D01*
G01X853081Y-189647D02*
X855702Y-194314D01*
G01X864032Y-176814D02*
Y-189356D01*
X864905Y-191981D01*
X866652Y-193731D01*
X868835Y-194314D01*
X871018Y-193731D01*
X872765Y-191981D01*
X873638Y-189356D01*
Y-176814D01*
G01X883715D02*
X888955D01*
G01X886335D02*
Y-194314D01*
G01X883715D02*
X888955D01*
G01X898813D02*
Y-176814D01*
X908857Y-194314D01*
Y-176814D01*
G01X926138Y-178273D02*
X924828Y-177397D01*
X923300Y-176814D01*
X921553D01*
X919588Y-177689D01*
X918060Y-179147D01*
X916968Y-180898D01*
X916095Y-183814D01*
X915876Y-186439D01*
X916313Y-189064D01*
X916968Y-190814D01*
X918278Y-192564D01*
X919807Y-193731D01*
X921335Y-194314D01*
X922863D01*
X924392Y-193731D01*
X925702Y-192856D01*
X926794Y-191690D01*
G01X938835Y-194314D02*
Y-186439D01*
X934468Y-176814D01*
G01X943202D02*
X938835Y-186439D01*
G01X829032Y-149314D02*
Y-131814D01*
X833398D01*
X835145Y-132689D01*
X836455Y-133856D01*
X837547Y-135605D01*
X838420Y-137648D01*
X838638Y-140564D01*
X838420Y-143481D01*
X837547Y-145523D01*
X836455Y-147273D01*
X835145Y-148439D01*
X833398Y-149314D01*
X829032D01*
G01X848060Y-141439D02*
X855047D01*
X854392Y-139397D01*
X853300Y-138231D01*
X851772Y-137648D01*
X850243Y-137939D01*
X848933Y-138814D01*
X848060Y-140856D01*
X847623Y-142606D01*
Y-144356D01*
X848060Y-146106D01*
X849152Y-147856D01*
X850462Y-149022D01*
X851990Y-149314D01*
X853518Y-148731D01*
X855047Y-146981D01*
G01X865560Y-147273D02*
X866652Y-148439D01*
X868180Y-149314D01*
X869490D01*
X870800Y-148731D01*
X871673Y-147856D01*
X872110Y-146690D01*
X871892Y-144939D01*
X871018Y-144064D01*
X867088Y-142314D01*
X866215Y-140272D01*
X866652Y-138814D01*
X867525Y-137939D01*
X868835Y-137648D01*
X870145Y-137939D01*
X871455Y-138814D01*
G01X886335Y-137648D02*
Y-149314D01*
G01Y-132981D02*
X885898Y-132689D01*
Y-132106D01*
X886335Y-131814D01*
X886772Y-132106D01*
Y-132689D01*
X886335Y-132981D01*
G01X900778Y-153689D02*
X902307Y-154856D01*
X904053Y-155147D01*
X905581Y-154856D01*
X906892Y-153398D01*
X907765Y-151356D01*
Y-137648D01*
G01Y-139981D02*
X906892Y-138814D01*
X905581Y-137939D01*
X904053Y-137648D01*
X902307Y-138231D01*
X901215Y-139397D01*
X900341Y-141439D01*
X899905Y-143481D01*
X900123Y-145231D01*
X900997Y-147273D01*
X902307Y-148731D01*
X904053Y-149314D01*
X905363Y-149022D01*
X906892Y-147856D01*
X907765Y-146690D01*
G01X917623Y-149314D02*
Y-137648D01*
G01Y-140564D02*
X918497Y-139106D01*
X919807Y-137939D01*
X921553Y-137648D01*
X923081Y-137939D01*
X924392Y-139106D01*
X925047Y-141147D01*
Y-149314D01*
G01X935560Y-141439D02*
X942547D01*
X941892Y-139397D01*
X940800Y-138231D01*
X939272Y-137648D01*
X937743Y-137939D01*
X936433Y-138814D01*
X935560Y-140856D01*
X935123Y-142606D01*
Y-144356D01*
X935560Y-146106D01*
X936652Y-147856D01*
X937962Y-149022D01*
X939490Y-149314D01*
X941018Y-148731D01*
X942547Y-146981D01*
G01X953278Y-149314D02*
Y-137648D01*
G01Y-139981D02*
X954370Y-138814D01*
X955462Y-137939D01*
X956990Y-137648D01*
X958081Y-137939D01*
X959392Y-138814D01*
G01X918285Y272200D02*
Y284700D01*
X925415Y272200D01*
Y284700D01*
G01X934250Y272200D02*
X933320Y272408D01*
X932390Y273241D01*
X931770Y274700D01*
X931460Y276367D01*
X931770Y278033D01*
X932390Y279492D01*
X933320Y280325D01*
X934250Y280533D01*
X935180Y280325D01*
X936110Y279492D01*
X936730Y278033D01*
X936885Y276367D01*
X936730Y274700D01*
X936110Y273241D01*
X935180Y272408D01*
X934250Y272200D01*
G01X946650Y284700D02*
Y272200D01*
G01X944480Y280533D02*
X948820D01*
G01X956725Y277825D02*
X961685D01*
X961220Y279283D01*
X960445Y280117D01*
X959360Y280533D01*
X958275Y280325D01*
X957345Y279700D01*
X956725Y278242D01*
X956415Y276991D01*
Y275742D01*
X956725Y274492D01*
X957500Y273241D01*
X958430Y272408D01*
X959515Y272200D01*
X960600Y272617D01*
X961685Y273866D01*
G01X971450Y271783D02*
X971140Y271992D01*
Y272408D01*
X971450Y272617D01*
X971760Y272408D01*
Y271992D01*
X971450Y271783D01*
G01Y277408D02*
X971140Y277617D01*
Y278033D01*
X971450Y278242D01*
X971760Y278033D01*
Y277617D01*
X971450Y277408D01*
G01X980750Y272200D02*
Y284700D01*
X984625D01*
X985865Y284075D01*
X986640Y283242D01*
X986950Y281575D01*
X986640Y279908D01*
X985710Y278867D01*
X984625Y278242D01*
X980750D01*
G01X984625D02*
X986950Y272200D01*
G01X993925Y277825D02*
X998885D01*
X998420Y279283D01*
X997645Y280117D01*
X996560Y280533D01*
X995475Y280325D01*
X994545Y279700D01*
X993925Y278242D01*
X993615Y276991D01*
Y275742D01*
X993925Y274492D01*
X994700Y273241D01*
X995630Y272408D01*
X996715Y272200D01*
X997800Y272617D01*
X998885Y273866D01*
G01X1007720Y272200D02*
Y282825D01*
X1008030Y283866D01*
X1008650Y284492D01*
X1009580Y284700D01*
X1010510Y284283D01*
X1010975Y283242D01*
G01X1009115Y279700D02*
X1006015D01*
G01X1018725Y277825D02*
X1023685D01*
X1023220Y279283D01*
X1022445Y280117D01*
X1021360Y280533D01*
X1020275Y280325D01*
X1019345Y279700D01*
X1018725Y278242D01*
X1018415Y276991D01*
Y275742D01*
X1018725Y274492D01*
X1019500Y273241D01*
X1020430Y272408D01*
X1021515Y272200D01*
X1022600Y272617D01*
X1023685Y273866D01*
G01X1031280Y272200D02*
Y280533D01*
G01Y278867D02*
X1032055Y279700D01*
X1032830Y280325D01*
X1033915Y280533D01*
X1034690Y280325D01*
X1035620Y279700D01*
G01X1058250Y284700D02*
Y272200D01*
G01X1056080Y280533D02*
X1060420D01*
G01X1070650Y272200D02*
X1069720Y272408D01*
X1068790Y273241D01*
X1068170Y274700D01*
X1067860Y276367D01*
X1068170Y278033D01*
X1068790Y279492D01*
X1069720Y280325D01*
X1070650Y280533D01*
X1071580Y280325D01*
X1072510Y279492D01*
X1073130Y278033D01*
X1073285Y276367D01*
X1073130Y274700D01*
X1072510Y273241D01*
X1071580Y272408D01*
X1070650Y272200D01*
G01X1092040D02*
Y284700D01*
X1095140D01*
X1096380Y284075D01*
X1097310Y283242D01*
X1098085Y281992D01*
X1098705Y280533D01*
X1098860Y278450D01*
X1098705Y276367D01*
X1098085Y274908D01*
X1097310Y273658D01*
X1096380Y272825D01*
X1095140Y272200D01*
X1092040D01*
G01X1104750D02*
Y284700D01*
X1108625D01*
X1109865Y284075D01*
X1110640Y283242D01*
X1110950Y281575D01*
X1110640Y279908D01*
X1109710Y278867D01*
X1108625Y278242D01*
X1104750D01*
G01X1108625D02*
X1110950Y272200D01*
G01X1118390Y284700D02*
X1122110D01*
G01X1120250D02*
Y272200D01*
G01X1118390D02*
X1122110D01*
G01X1129550Y284700D02*
Y272200D01*
X1135750D01*
G01X1141950Y284700D02*
Y272200D01*
X1148150D01*
G01X1169850D02*
Y284700D01*
G01X1185040Y272200D02*
Y280533D01*
G01Y279075D02*
X1184420Y279908D01*
X1183490Y280325D01*
X1182405Y280533D01*
X1181320Y280117D01*
X1180390Y279283D01*
X1179770Y278033D01*
X1179460Y276367D01*
X1179770Y274700D01*
X1180390Y273450D01*
X1181320Y272617D01*
X1182405Y272200D01*
X1183490Y272408D01*
X1184420Y273033D01*
X1185040Y273866D01*
G01X1191395Y268450D02*
X1192325Y268033D01*
X1193565Y268450D01*
X1194340Y269283D01*
X1194960Y270325D01*
X1195890Y273658D01*
X1197905Y280533D01*
G01X1192945D02*
X1195890Y273658D01*
G01X1204725Y277825D02*
X1209685D01*
X1209220Y279283D01*
X1208445Y280117D01*
X1207360Y280533D01*
X1206275Y280325D01*
X1205345Y279700D01*
X1204725Y278242D01*
X1204415Y276991D01*
Y275742D01*
X1204725Y274492D01*
X1205500Y273241D01*
X1206430Y272408D01*
X1207515Y272200D01*
X1208600Y272617D01*
X1209685Y273866D01*
G01X1217280Y272200D02*
Y280533D01*
G01Y278867D02*
X1218055Y279700D01*
X1218830Y280325D01*
X1219915Y280533D01*
X1220690Y280325D01*
X1221620Y279700D01*
G01X1243320Y272200D02*
Y282825D01*
X1243630Y283866D01*
X1244250Y284492D01*
X1245180Y284700D01*
X1246110Y284283D01*
X1246575Y283242D01*
G01X1244715Y279700D02*
X1241615D01*
G01X1256650Y272200D02*
X1255720Y272408D01*
X1254790Y273241D01*
X1254170Y274700D01*
X1253860Y276367D01*
X1254170Y278033D01*
X1254790Y279492D01*
X1255720Y280325D01*
X1256650Y280533D01*
X1257580Y280325D01*
X1258510Y279492D01*
X1259130Y278033D01*
X1259285Y276367D01*
X1259130Y274700D01*
X1258510Y273241D01*
X1257580Y272408D01*
X1256650Y272200D01*
G01X1266880D02*
Y280533D01*
G01Y278867D02*
X1267655Y279700D01*
X1268430Y280325D01*
X1269515Y280533D01*
X1270290Y280325D01*
X1271220Y279700D01*
G01X1296950Y272200D02*
X1290750D01*
Y284700D01*
X1296950D01*
G01X1294470Y278658D02*
X1290750D01*
G01X1303150Y284700D02*
Y272200D01*
X1309350D01*
G01X1315550Y284700D02*
Y272200D01*
X1321750D01*
G01X1329190Y284700D02*
X1332910D01*
G01X1331050D02*
Y272200D01*
G01X1329190D02*
X1332910D01*
G01X1340350D02*
Y284700D01*
X1344070D01*
X1345310Y284075D01*
X1346240Y282617D01*
X1346550Y280950D01*
X1346240Y279283D01*
X1345465Y278033D01*
X1344070Y277408D01*
X1340350D01*
G01X1352595Y273866D02*
X1353835Y272825D01*
X1355230Y272200D01*
X1356470D01*
X1357710Y272825D01*
X1358640Y273866D01*
X1359105Y275325D01*
X1358795Y276783D01*
X1358020Y278033D01*
X1356625Y278867D01*
X1354765Y279283D01*
X1353680Y280117D01*
X1353215Y281575D01*
X1353525Y283033D01*
X1354300Y284075D01*
X1355385Y284700D01*
X1356470D01*
X1357555Y284283D01*
X1358485Y283242D01*
G01X1371350Y272200D02*
X1365150D01*
Y284700D01*
X1371350D01*
G01X1368870Y278658D02*
X1365150D01*
G01X1395840Y284700D02*
Y272200D01*
G01Y274075D02*
X1395220Y273033D01*
X1394290Y272408D01*
X1393205Y272200D01*
X1391965Y272617D01*
X1391035Y273658D01*
X1390415Y274908D01*
X1390260Y276367D01*
X1390415Y277825D01*
X1391035Y279075D01*
X1391965Y280117D01*
X1393205Y280533D01*
X1394290Y280325D01*
X1395065Y279908D01*
X1395840Y279075D01*
G01X1403280Y272200D02*
Y280533D01*
G01Y278867D02*
X1404055Y279700D01*
X1404830Y280325D01*
X1405915Y280533D01*
X1406690Y280325D01*
X1407620Y279700D01*
G01X1417850Y280533D02*
Y272200D01*
G01Y283866D02*
X1417540Y284075D01*
Y284492D01*
X1417850Y284700D01*
X1418160Y284492D01*
Y284075D01*
X1417850Y283866D01*
G01X1430250Y272200D02*
Y284700D01*
G01X1442650Y272200D02*
Y284700D01*
G01X1470240D02*
Y272200D01*
G01Y274075D02*
X1469620Y273033D01*
X1468690Y272408D01*
X1467605Y272200D01*
X1466365Y272617D01*
X1465435Y273658D01*
X1464815Y274908D01*
X1464660Y276367D01*
X1464815Y277825D01*
X1465435Y279075D01*
X1466365Y280117D01*
X1467605Y280533D01*
X1468690Y280325D01*
X1469465Y279908D01*
X1470240Y279075D01*
G01X1479850Y280533D02*
Y272200D01*
G01Y283866D02*
X1479540Y284075D01*
Y284492D01*
X1479850Y284700D01*
X1480160Y284492D01*
Y284075D01*
X1479850Y283866D01*
G01X1490080Y272200D02*
Y280533D01*
G01Y278867D02*
X1490855Y279700D01*
X1491630Y280325D01*
X1492715Y280533D01*
X1493490Y280325D01*
X1494420Y279700D01*
G01X1502325Y277825D02*
X1507285D01*
X1506820Y279283D01*
X1506045Y280117D01*
X1504960Y280533D01*
X1503875Y280325D01*
X1502945Y279700D01*
X1502325Y278242D01*
X1502015Y276991D01*
Y275742D01*
X1502325Y274492D01*
X1503100Y273241D01*
X1504030Y272408D01*
X1505115Y272200D01*
X1506200Y272617D01*
X1507285Y273866D01*
G01X1519530Y279492D02*
X1518445Y280325D01*
X1517515Y280533D01*
X1516275Y280117D01*
X1515345Y279283D01*
X1514725Y277825D01*
X1514570Y276367D01*
X1514725Y274908D01*
X1515345Y273658D01*
X1516275Y272617D01*
X1517515Y272200D01*
X1518600Y272617D01*
X1519530Y273450D01*
G01X1529450Y284700D02*
Y272200D01*
G01X1527280Y280533D02*
X1531620D01*
G01X1541850D02*
Y272200D01*
G01Y283866D02*
X1541540Y284075D01*
Y284492D01*
X1541850Y284700D01*
X1542160Y284492D01*
Y284075D01*
X1541850Y283866D01*
G01X1554250Y272200D02*
X1553320Y272408D01*
X1552390Y273241D01*
X1551770Y274700D01*
X1551460Y276367D01*
X1551770Y278033D01*
X1552390Y279492D01*
X1553320Y280325D01*
X1554250Y280533D01*
X1555180Y280325D01*
X1556110Y279492D01*
X1556730Y278033D01*
X1556885Y276367D01*
X1556730Y274700D01*
X1556110Y273241D01*
X1555180Y272408D01*
X1554250Y272200D01*
G01X1564015D02*
Y280533D01*
G01Y278450D02*
X1564635Y279492D01*
X1565565Y280325D01*
X1566805Y280533D01*
X1567890Y280325D01*
X1568820Y279492D01*
X1569285Y278033D01*
Y272200D01*
G01X917200Y302200D02*
Y495800D01*
X1400800D01*
Y302200D01*
X917200D01*
G01Y330300D02*
X1400800D01*
G01X917200Y386500D02*
X1400800D01*
G01X917200Y358400D02*
X1400800D01*
G01X928205Y423950D02*
Y436450D01*
X934095D01*
G01X931925Y430408D02*
X928205D01*
G01X941690Y436450D02*
X945410D01*
G01X943550D02*
Y423950D01*
G01X941690D02*
X945410D01*
G01X956880Y430200D02*
X959980D01*
Y426450D01*
X959050Y425200D01*
X957965Y424367D01*
X956415Y423950D01*
X954865Y424367D01*
X953780Y425200D01*
X952850Y426450D01*
X952230Y427908D01*
X951920Y429575D01*
Y431033D01*
X952230Y432283D01*
X952850Y433742D01*
X953780Y434992D01*
X954710Y435825D01*
X955950Y436450D01*
X957035D01*
X958275Y436033D01*
X959205Y435200D01*
G01X964940Y436450D02*
Y427492D01*
X965560Y425616D01*
X966800Y424367D01*
X968350Y423950D01*
X969900Y424367D01*
X971140Y425616D01*
X971760Y427492D01*
Y436450D01*
G01X977650Y423950D02*
Y436450D01*
X981525D01*
X982765Y435825D01*
X983540Y434992D01*
X983850Y433325D01*
X983540Y431658D01*
X982610Y430617D01*
X981525Y429992D01*
X977650D01*
G01X981525D02*
X983850Y423950D01*
G01X996250D02*
X990050D01*
Y436450D01*
X996250D01*
G01X993770Y430408D02*
X990050D01*
G01X917200Y442700D02*
X1400800D01*
G01X917200Y414600D02*
X1400800D01*
G01X917200Y470800D02*
X1400800D01*
G01X1000035Y-176814D02*
X998288Y-177397D01*
X996978Y-178856D01*
X996105Y-180605D01*
X995450Y-182939D01*
X995232Y-185564D01*
X995450Y-188189D01*
X996105Y-190523D01*
X996978Y-192273D01*
X998288Y-193731D01*
X1000035Y-194314D01*
X1001781Y-193731D01*
X1003092Y-192273D01*
X1003965Y-190523D01*
X1004620Y-188189D01*
X1004838Y-185564D01*
X1004620Y-182939D01*
X1003965Y-180605D01*
X1003092Y-178856D01*
X1001781Y-177397D01*
X1000035Y-176814D01*
G01X1012732Y-190814D02*
X1014041Y-192856D01*
X1015788Y-194022D01*
X1017753Y-194314D01*
X1019500Y-194022D01*
X1021247Y-192564D01*
X1022338Y-190814D01*
X1022557Y-189064D01*
X1022120Y-187023D01*
X1020592Y-185564D01*
X1019063Y-184981D01*
X1017098D01*
G01X1019063D02*
X1020373Y-184106D01*
X1021465Y-182648D01*
X1021902Y-180898D01*
X1021465Y-179147D01*
X1020373Y-177689D01*
X1018408Y-176814D01*
X1016443Y-177106D01*
X1014478Y-178273D01*
G01X1031105Y-194897D02*
X1038965Y-176814D01*
G01X1052535Y-194314D02*
Y-176814D01*
X1049915Y-180314D01*
G01Y-194314D02*
X1055155D01*
G01X1065232Y-190814D02*
X1066541Y-192856D01*
X1068288Y-194022D01*
X1070253Y-194314D01*
X1072000Y-194022D01*
X1073747Y-192564D01*
X1074838Y-190814D01*
X1075057Y-189064D01*
X1074620Y-187023D01*
X1073092Y-185564D01*
X1071563Y-184981D01*
X1069598D01*
G01X1071563D02*
X1072873Y-184106D01*
X1073965Y-182648D01*
X1074402Y-180898D01*
X1073965Y-179147D01*
X1072873Y-177689D01*
X1070908Y-176814D01*
X1068943Y-177106D01*
X1066978Y-178273D01*
G01X1083605Y-194897D02*
X1091465Y-176814D01*
G01X1100887Y-179731D02*
X1102197Y-177981D01*
X1103725Y-177106D01*
X1105472Y-176814D01*
X1107655Y-177397D01*
X1109183Y-178856D01*
X1109620Y-180605D01*
X1109402Y-182356D01*
X1108528Y-183814D01*
X1104162Y-186731D01*
X1102197Y-188772D01*
X1100887Y-191690D01*
X1100450Y-194314D01*
X1109620D01*
G01X1122535Y-176814D02*
X1120788Y-177397D01*
X1119478Y-178856D01*
X1118605Y-180605D01*
X1117950Y-182939D01*
X1117732Y-185564D01*
X1117950Y-188189D01*
X1118605Y-190523D01*
X1119478Y-192273D01*
X1120788Y-193731D01*
X1122535Y-194314D01*
X1124281Y-193731D01*
X1125592Y-192273D01*
X1126465Y-190523D01*
X1127120Y-188189D01*
X1127338Y-185564D01*
X1127120Y-182939D01*
X1126465Y-180605D01*
X1125592Y-178856D01*
X1124281Y-177397D01*
X1122535Y-176814D01*
G01X1140035Y-194314D02*
Y-176814D01*
X1137415Y-180314D01*
G01Y-194314D02*
X1142655D01*
G01X1157098D02*
X1157535Y-190523D01*
X1158190Y-187314D01*
X1159063Y-184397D01*
X1160155Y-181189D01*
X1161902Y-176814D01*
X1153168D01*
G01X1007100Y442700D02*
Y302200D01*
G01X1031125Y452050D02*
X1035000Y464550D01*
X1038875Y452050D01*
G01X1037480Y456425D02*
X1032520D01*
G01X1044300Y464550D02*
Y452050D01*
X1050500D01*
G01X1056700Y464550D02*
Y452050D01*
X1062900D01*
G01X1081190Y464550D02*
Y455592D01*
X1081810Y453716D01*
X1083050Y452467D01*
X1084600Y452050D01*
X1086150Y452467D01*
X1087390Y453716D01*
X1088010Y455592D01*
Y464550D01*
G01X1093435Y452050D02*
Y464550D01*
X1100565Y452050D01*
Y464550D01*
G01X1107540D02*
X1111260D01*
G01X1109400D02*
Y452050D01*
G01X1107540D02*
X1111260D01*
G01X1121800Y464550D02*
Y452050D01*
G01X1118235Y464550D02*
X1125365D01*
G01X1130945Y453716D02*
X1132185Y452675D01*
X1133580Y452050D01*
X1134820D01*
X1136060Y452675D01*
X1136990Y453716D01*
X1137455Y455175D01*
X1137145Y456633D01*
X1136370Y457883D01*
X1134975Y458717D01*
X1133115Y459133D01*
X1132030Y459967D01*
X1131565Y461425D01*
X1131875Y462883D01*
X1132650Y463925D01*
X1133735Y464550D01*
X1134820D01*
X1135905Y464133D01*
X1136835Y463092D01*
G01X1155125Y452050D02*
X1159000Y464550D01*
X1162875Y452050D01*
G01X1161480Y456425D02*
X1156520D01*
G01X1168300Y452050D02*
Y464550D01*
X1172175D01*
X1173415Y463925D01*
X1174190Y463092D01*
X1174500Y461425D01*
X1174190Y459758D01*
X1173260Y458717D01*
X1172175Y458092D01*
X1168300D01*
G01X1172175D02*
X1174500Y452050D01*
G01X1186900D02*
X1180700D01*
Y464550D01*
X1186900D01*
G01X1184420Y458508D02*
X1180700D01*
G01X1206740Y464550D02*
X1210460D01*
G01X1208600D02*
Y452050D01*
G01X1206740D02*
X1210460D01*
G01X1217435D02*
Y464550D01*
X1224565Y452050D01*
Y464550D01*
G01X1241770Y452050D02*
Y464550D01*
X1245800Y454133D01*
X1249830Y464550D01*
Y452050D01*
G01X1256340Y464550D02*
X1260060D01*
G01X1258200D02*
Y452050D01*
G01X1256340D02*
X1260060D01*
G01X1267500Y464550D02*
Y452050D01*
X1273700D01*
G01X1279745Y453716D02*
X1280985Y452675D01*
X1282380Y452050D01*
X1283620D01*
X1284860Y452675D01*
X1285790Y453716D01*
X1286255Y455175D01*
X1285945Y456633D01*
X1285170Y457883D01*
X1283775Y458717D01*
X1281915Y459133D01*
X1280830Y459967D01*
X1280365Y461425D01*
X1280675Y462883D01*
X1281450Y463925D01*
X1282535Y464550D01*
X1283620D01*
X1284705Y464133D01*
X1285635Y463092D01*
G01X1000590Y477050D02*
Y489550D01*
X1003690D01*
X1004930Y488925D01*
X1005860Y488092D01*
X1006635Y486842D01*
X1007255Y485383D01*
X1007410Y483300D01*
X1007255Y481217D01*
X1006635Y479758D01*
X1005860Y478508D01*
X1004930Y477675D01*
X1003690Y477050D01*
X1000590D01*
G01X1013300D02*
Y489550D01*
X1017175D01*
X1018415Y488925D01*
X1019190Y488092D01*
X1019500Y486425D01*
X1019190Y484758D01*
X1018260Y483717D01*
X1017175Y483092D01*
X1013300D01*
G01X1017175D02*
X1019500Y477050D01*
G01X1026940Y489550D02*
X1030660D01*
G01X1028800D02*
Y477050D01*
G01X1026940D02*
X1030660D01*
G01X1038100Y489550D02*
Y477050D01*
X1044300D01*
G01X1050500Y489550D02*
Y477050D01*
X1056700D01*
G01X1081810Y488508D02*
X1080880Y489133D01*
X1079795Y489550D01*
X1078555D01*
X1077160Y488925D01*
X1076075Y487883D01*
X1075300Y486633D01*
X1074680Y484550D01*
X1074525Y482675D01*
X1074835Y480800D01*
X1075300Y479550D01*
X1076230Y478300D01*
X1077315Y477467D01*
X1078400Y477050D01*
X1079485D01*
X1080570Y477467D01*
X1081500Y478091D01*
X1082275Y478925D01*
G01X1087545Y477050D02*
Y489550D01*
G01X1094055D02*
Y477050D01*
G01Y483300D02*
X1087545D01*
G01X1099325Y477050D02*
X1103200Y489550D01*
X1107075Y477050D01*
G01X1105680Y481425D02*
X1100720D01*
G01X1112500Y477050D02*
Y489550D01*
X1116375D01*
X1117615Y488925D01*
X1118390Y488092D01*
X1118700Y486425D01*
X1118390Y484758D01*
X1117460Y483717D01*
X1116375Y483092D01*
X1112500D01*
G01X1116375D02*
X1118700Y477050D01*
G01X1128000Y489550D02*
Y477050D01*
G01X1124435Y489550D02*
X1131565D01*
G01X1140400Y476633D02*
X1140090Y476842D01*
Y477258D01*
X1140400Y477467D01*
X1140710Y477258D01*
Y476842D01*
X1140400Y476633D01*
G01Y482258D02*
X1140090Y482467D01*
Y482883D01*
X1140400Y483092D01*
X1140710Y482883D01*
Y482467D01*
X1140400Y482258D01*
G01X1165200Y489550D02*
Y477050D01*
G01X1161635Y489550D02*
X1168765D01*
G01X1177600Y477050D02*
X1176360Y477258D01*
X1175275Y478091D01*
X1174345Y479342D01*
X1173725Y480800D01*
X1173415Y482467D01*
Y484133D01*
X1173725Y485800D01*
X1174345Y487258D01*
X1175275Y488508D01*
X1176360Y489342D01*
X1177600Y489550D01*
X1178840Y489342D01*
X1179925Y488508D01*
X1180855Y487258D01*
X1181475Y485800D01*
X1181785Y484133D01*
Y482467D01*
X1181475Y480800D01*
X1180855Y479342D01*
X1179925Y478091D01*
X1178840Y477258D01*
X1177600Y477050D01*
G01X1186900D02*
Y489550D01*
X1190620D01*
X1191860Y488925D01*
X1192790Y487467D01*
X1193100Y485800D01*
X1192790Y484133D01*
X1192015Y482883D01*
X1190620Y482258D01*
X1186900D01*
G01X1214800Y489550D02*
Y477050D01*
G01X1212630Y485383D02*
X1216970D01*
G01X1227200Y477050D02*
X1226270Y477258D01*
X1225340Y478091D01*
X1224720Y479550D01*
X1224410Y481217D01*
X1224720Y482883D01*
X1225340Y484342D01*
X1226270Y485175D01*
X1227200Y485383D01*
X1228130Y485175D01*
X1229060Y484342D01*
X1229680Y482883D01*
X1229835Y481217D01*
X1229680Y479550D01*
X1229060Y478091D01*
X1228130Y477258D01*
X1227200Y477050D01*
G01X1253240Y483717D02*
X1253860Y484342D01*
X1254325Y485383D01*
X1254635Y486842D01*
X1254325Y488092D01*
X1253705Y488925D01*
X1252620Y489550D01*
X1248435D01*
Y477050D01*
X1253550D01*
X1254635Y477883D01*
X1255255Y479133D01*
X1255565Y480592D01*
X1255255Y482050D01*
X1254325Y483300D01*
X1253240Y483717D01*
X1248435D01*
G01X1264400Y477050D02*
X1263160Y477258D01*
X1262075Y478091D01*
X1261145Y479342D01*
X1260525Y480800D01*
X1260215Y482467D01*
Y484133D01*
X1260525Y485800D01*
X1261145Y487258D01*
X1262075Y488508D01*
X1263160Y489342D01*
X1264400Y489550D01*
X1265640Y489342D01*
X1266725Y488508D01*
X1267655Y487258D01*
X1268275Y485800D01*
X1268585Y484133D01*
Y482467D01*
X1268275Y480800D01*
X1267655Y479342D01*
X1266725Y478091D01*
X1265640Y477258D01*
X1264400Y477050D01*
G01X1276800Y489550D02*
Y477050D01*
G01X1273235Y489550D02*
X1280365D01*
G01X1289200D02*
Y477050D01*
G01X1285635Y489550D02*
X1292765D01*
G01X1301600Y477050D02*
X1300360Y477258D01*
X1299275Y478091D01*
X1298345Y479342D01*
X1297725Y480800D01*
X1297415Y482467D01*
Y484133D01*
X1297725Y485800D01*
X1298345Y487258D01*
X1299275Y488508D01*
X1300360Y489342D01*
X1301600Y489550D01*
X1302840Y489342D01*
X1303925Y488508D01*
X1304855Y487258D01*
X1305475Y485800D01*
X1305785Y484133D01*
Y482467D01*
X1305475Y480800D01*
X1304855Y479342D01*
X1303925Y478091D01*
X1302840Y477258D01*
X1301600Y477050D01*
G01X1309970D02*
Y489550D01*
X1314000Y479133D01*
X1318030Y489550D01*
Y477050D01*
G01X1047732Y-149314D02*
Y-131814D01*
X1052098D01*
X1053845Y-132689D01*
X1055155Y-133856D01*
X1056247Y-135605D01*
X1057120Y-137648D01*
X1057338Y-140564D01*
X1057120Y-143481D01*
X1056247Y-145523D01*
X1055155Y-147273D01*
X1053845Y-148439D01*
X1052098Y-149314D01*
X1047732D01*
G01X1073965D02*
Y-137648D01*
G01Y-139689D02*
X1073092Y-138523D01*
X1071781Y-137939D01*
X1070253Y-137648D01*
X1068725Y-138231D01*
X1067415Y-139397D01*
X1066541Y-141147D01*
X1066105Y-143481D01*
X1066541Y-145814D01*
X1067415Y-147564D01*
X1068725Y-148731D01*
X1070253Y-149314D01*
X1071781Y-149022D01*
X1073092Y-148148D01*
X1073965Y-146981D01*
G01X1087535Y-131814D02*
Y-149314D01*
G01X1084478Y-137648D02*
X1090592D01*
G01X1101760Y-141439D02*
X1108747D01*
X1108092Y-139397D01*
X1107000Y-138231D01*
X1105472Y-137648D01*
X1103943Y-137939D01*
X1102633Y-138814D01*
X1101760Y-140856D01*
X1101323Y-142606D01*
Y-144356D01*
X1101760Y-146106D01*
X1102852Y-147856D01*
X1104162Y-149022D01*
X1105690Y-149314D01*
X1107218Y-148731D01*
X1108747Y-146981D01*
G01X1076850Y310000D02*
Y322500D01*
X1074990Y320000D01*
G01Y310000D02*
X1078710D01*
G01X1089250D02*
Y322500D01*
X1087390Y320000D01*
G01Y310000D02*
X1091110D01*
G01X1098240Y311875D02*
X1099170Y310833D01*
X1100255Y310208D01*
X1101650Y310000D01*
X1103045Y310417D01*
X1104130Y311250D01*
X1104905Y312708D01*
X1105060Y314375D01*
X1104750Y316042D01*
X1103975Y317083D01*
X1102890Y317917D01*
X1101805Y318125D01*
X1100720Y317917D01*
X1099325Y317083D01*
X1099790Y322500D01*
X1103975D01*
G01X1114050Y309583D02*
X1113740Y309792D01*
Y310208D01*
X1114050Y310417D01*
X1114360Y310208D01*
Y309792D01*
X1114050Y309583D01*
G01X1126450Y322500D02*
X1125210Y322083D01*
X1124280Y321042D01*
X1123660Y319792D01*
X1123195Y318125D01*
X1123040Y316250D01*
X1123195Y314375D01*
X1123660Y312708D01*
X1124280Y311458D01*
X1125210Y310417D01*
X1126450Y310000D01*
X1127690Y310417D01*
X1128620Y311458D01*
X1129240Y312708D01*
X1129705Y314375D01*
X1129860Y316250D01*
X1129705Y318125D01*
X1129240Y319792D01*
X1128620Y321042D01*
X1127690Y322083D01*
X1126450Y322500D01*
G01X1083050Y338100D02*
X1084135Y338308D01*
X1085375Y338933D01*
X1086150Y339975D01*
X1086460Y341433D01*
X1086150Y342891D01*
X1085220Y344142D01*
X1083825Y344767D01*
X1082275D01*
X1081345Y345183D01*
X1080570Y346225D01*
X1080260Y347683D01*
X1080725Y349142D01*
X1081810Y350183D01*
X1083050Y350600D01*
X1084290Y350183D01*
X1085375Y349142D01*
X1085840Y347683D01*
X1085530Y346225D01*
X1084755Y345183D01*
X1083825Y344767D01*
X1082275D01*
X1080880Y344142D01*
X1079950Y342891D01*
X1079640Y341433D01*
X1079950Y339975D01*
X1080725Y338933D01*
X1081965Y338308D01*
X1083050Y338100D01*
G01X1092505Y343308D02*
X1093590Y344767D01*
X1094520Y345600D01*
X1095760Y346017D01*
X1096845Y345600D01*
X1097620Y344767D01*
X1098240Y343517D01*
X1098395Y342058D01*
X1098240Y340808D01*
X1097620Y339558D01*
X1096690Y338517D01*
X1095605Y338100D01*
X1094365Y338517D01*
X1093280Y339766D01*
X1092660Y341642D01*
X1092505Y343725D01*
X1092815Y346433D01*
X1093280Y347892D01*
X1094055Y349350D01*
X1095140Y350392D01*
X1096225Y350600D01*
X1097310Y350183D01*
X1098085Y349142D01*
G01X1107850Y337683D02*
X1107540Y337892D01*
Y338308D01*
X1107850Y338517D01*
X1108160Y338308D01*
Y337892D01*
X1107850Y337683D01*
G01X1120250Y350600D02*
X1119010Y350183D01*
X1118080Y349142D01*
X1117460Y347892D01*
X1116995Y346225D01*
X1116840Y344350D01*
X1116995Y342475D01*
X1117460Y340808D01*
X1118080Y339558D01*
X1119010Y338517D01*
X1120250Y338100D01*
X1121490Y338517D01*
X1122420Y339558D01*
X1123040Y340808D01*
X1123505Y342475D01*
X1123660Y344350D01*
X1123505Y346225D01*
X1123040Y347892D01*
X1122420Y349142D01*
X1121490Y350183D01*
X1120250Y350600D01*
G01X1083050Y394300D02*
Y406800D01*
X1081190Y404300D01*
G01Y394300D02*
X1084910D01*
G01X1092505Y404717D02*
X1093435Y405966D01*
X1094520Y406592D01*
X1095760Y406800D01*
X1097310Y406383D01*
X1098395Y405342D01*
X1098705Y404092D01*
X1098550Y402841D01*
X1097930Y401800D01*
X1094830Y399717D01*
X1093435Y398258D01*
X1092505Y396175D01*
X1092195Y394300D01*
X1098705D01*
G01X1107850Y393883D02*
X1107540Y394092D01*
Y394508D01*
X1107850Y394717D01*
X1108160Y394508D01*
Y394092D01*
X1107850Y393883D01*
G01X1120250Y406800D02*
X1119010Y406383D01*
X1118080Y405342D01*
X1117460Y404092D01*
X1116995Y402425D01*
X1116840Y400550D01*
X1116995Y398675D01*
X1117460Y397008D01*
X1118080Y395758D01*
X1119010Y394717D01*
X1120250Y394300D01*
X1121490Y394717D01*
X1122420Y395758D01*
X1123040Y397008D01*
X1123505Y398675D01*
X1123660Y400550D01*
X1123505Y402425D01*
X1123040Y404092D01*
X1122420Y405342D01*
X1121490Y406383D01*
X1120250Y406800D01*
G01X1076850Y366200D02*
Y378700D01*
X1074990Y376200D01*
G01Y366200D02*
X1078710D01*
G01X1089250Y378700D02*
X1088010Y378283D01*
X1087080Y377242D01*
X1086460Y375992D01*
X1085995Y374325D01*
X1085840Y372450D01*
X1085995Y370575D01*
X1086460Y368908D01*
X1087080Y367658D01*
X1088010Y366617D01*
X1089250Y366200D01*
X1090490Y366617D01*
X1091420Y367658D01*
X1092040Y368908D01*
X1092505Y370575D01*
X1092660Y372450D01*
X1092505Y374325D01*
X1092040Y375992D01*
X1091420Y377242D01*
X1090490Y378283D01*
X1089250Y378700D01*
G01X1101650Y366200D02*
Y378700D01*
X1099790Y376200D01*
G01Y366200D02*
X1103510D01*
G01X1114050Y365783D02*
X1113740Y365992D01*
Y366408D01*
X1114050Y366617D01*
X1114360Y366408D01*
Y365992D01*
X1114050Y365783D01*
G01X1126450Y378700D02*
X1125210Y378283D01*
X1124280Y377242D01*
X1123660Y375992D01*
X1123195Y374325D01*
X1123040Y372450D01*
X1123195Y370575D01*
X1123660Y368908D01*
X1124280Y367658D01*
X1125210Y366617D01*
X1126450Y366200D01*
X1127690Y366617D01*
X1128620Y367658D01*
X1129240Y368908D01*
X1129705Y370575D01*
X1129860Y372450D01*
X1129705Y374325D01*
X1129240Y375992D01*
X1128620Y377242D01*
X1127690Y378283D01*
X1126450Y378700D01*
G01X1079795Y425616D02*
X1081035Y424575D01*
X1082430Y423950D01*
X1083670D01*
X1084910Y424575D01*
X1085840Y425616D01*
X1086305Y427075D01*
X1085995Y428533D01*
X1085220Y429783D01*
X1083825Y430617D01*
X1081965Y431033D01*
X1080880Y431867D01*
X1080415Y433325D01*
X1080725Y434783D01*
X1081500Y435825D01*
X1082585Y436450D01*
X1083670D01*
X1084755Y436033D01*
X1085685Y434992D01*
G01X1093590Y436450D02*
X1097310D01*
G01X1095450D02*
Y423950D01*
G01X1093590D02*
X1097310D01*
G01X1104905Y436450D02*
X1110795D01*
X1104905Y423950D01*
X1110795D01*
G01X1123350D02*
X1117150D01*
Y436450D01*
X1123350D01*
G01X1120870Y430408D02*
X1117150D01*
G01X1200385Y310000D02*
Y322500D01*
X1207515Y310000D01*
Y322500D01*
G01X1216350Y310000D02*
X1215110Y310208D01*
X1214025Y311041D01*
X1213095Y312292D01*
X1212475Y313750D01*
X1212165Y315417D01*
Y317083D01*
X1212475Y318750D01*
X1213095Y320208D01*
X1214025Y321458D01*
X1215110Y322292D01*
X1216350Y322500D01*
X1217590Y322292D01*
X1218675Y321458D01*
X1219605Y320208D01*
X1220225Y318750D01*
X1220535Y317083D01*
Y315417D01*
X1220225Y313750D01*
X1219605Y312292D01*
X1218675Y311041D01*
X1217590Y310208D01*
X1216350Y310000D01*
G01X1225185D02*
Y322500D01*
X1232315Y310000D01*
Y322500D01*
G01X1239135Y314167D02*
X1243165D01*
G01X1250450Y310000D02*
Y322500D01*
X1254170D01*
X1255410Y321875D01*
X1256340Y320417D01*
X1256650Y318750D01*
X1256340Y317083D01*
X1255565Y315833D01*
X1254170Y315208D01*
X1250450D01*
G01X1262850Y322500D02*
Y310000D01*
X1269050D01*
G01X1274475D02*
X1278350Y322500D01*
X1282225Y310000D01*
G01X1280830Y314375D02*
X1275870D01*
G01X1290750Y322500D02*
Y310000D01*
G01X1287185Y322500D02*
X1294315D01*
G01X1306250Y310000D02*
X1300050D01*
Y322500D01*
X1306250D01*
G01X1303770Y316458D02*
X1300050D01*
G01X1312140Y310000D02*
Y322500D01*
X1315240D01*
X1316480Y321875D01*
X1317410Y321042D01*
X1318185Y319792D01*
X1318805Y318333D01*
X1318960Y316250D01*
X1318805Y314167D01*
X1318185Y312708D01*
X1317410Y311458D01*
X1316480Y310625D01*
X1315240Y310000D01*
X1312140D01*
G01X1196200Y442700D02*
Y302200D01*
G01X1200385Y338100D02*
Y350600D01*
X1207515Y338100D01*
Y350600D01*
G01X1216350Y338100D02*
X1215110Y338308D01*
X1214025Y339141D01*
X1213095Y340392D01*
X1212475Y341850D01*
X1212165Y343517D01*
Y345183D01*
X1212475Y346850D01*
X1213095Y348308D01*
X1214025Y349558D01*
X1215110Y350392D01*
X1216350Y350600D01*
X1217590Y350392D01*
X1218675Y349558D01*
X1219605Y348308D01*
X1220225Y346850D01*
X1220535Y345183D01*
Y343517D01*
X1220225Y341850D01*
X1219605Y340392D01*
X1218675Y339141D01*
X1217590Y338308D01*
X1216350Y338100D01*
G01X1225185D02*
Y350600D01*
X1232315Y338100D01*
Y350600D01*
G01X1239135Y342267D02*
X1243165D01*
G01X1250450Y338100D02*
Y350600D01*
X1254170D01*
X1255410Y349975D01*
X1256340Y348517D01*
X1256650Y346850D01*
X1256340Y345183D01*
X1255565Y343933D01*
X1254170Y343308D01*
X1250450D01*
G01X1262850Y350600D02*
Y338100D01*
X1269050D01*
G01X1274475D02*
X1278350Y350600D01*
X1282225Y338100D01*
G01X1280830Y342475D02*
X1275870D01*
G01X1290750Y350600D02*
Y338100D01*
G01X1287185Y350600D02*
X1294315D01*
G01X1306250Y338100D02*
X1300050D01*
Y350600D01*
X1306250D01*
G01X1303770Y344558D02*
X1300050D01*
G01X1312140Y338100D02*
Y350600D01*
X1315240D01*
X1316480Y349975D01*
X1317410Y349142D01*
X1318185Y347892D01*
X1318805Y346433D01*
X1318960Y344350D01*
X1318805Y342267D01*
X1318185Y340808D01*
X1317410Y339558D01*
X1316480Y338725D01*
X1315240Y338100D01*
X1312140D01*
G01X1225650Y394300D02*
Y406800D01*
X1229370D01*
X1230610Y406175D01*
X1231540Y404717D01*
X1231850Y403050D01*
X1231540Y401383D01*
X1230765Y400133D01*
X1229370Y399508D01*
X1225650D01*
G01X1238050Y406800D02*
Y394300D01*
X1244250D01*
G01X1249675D02*
X1253550Y406800D01*
X1257425Y394300D01*
G01X1256030Y398675D02*
X1251070D01*
G01X1265950Y406800D02*
Y394300D01*
G01X1262385Y406800D02*
X1269515D01*
G01X1281450Y394300D02*
X1275250D01*
Y406800D01*
X1281450D01*
G01X1278970Y400758D02*
X1275250D01*
G01X1287340Y394300D02*
Y406800D01*
X1290440D01*
X1291680Y406175D01*
X1292610Y405342D01*
X1293385Y404092D01*
X1294005Y402633D01*
X1294160Y400550D01*
X1294005Y398467D01*
X1293385Y397008D01*
X1292610Y395758D01*
X1291680Y394925D01*
X1290440Y394300D01*
X1287340D01*
G01X1225650Y366200D02*
Y378700D01*
X1229370D01*
X1230610Y378075D01*
X1231540Y376617D01*
X1231850Y374950D01*
X1231540Y373283D01*
X1230765Y372033D01*
X1229370Y371408D01*
X1225650D01*
G01X1238050Y378700D02*
Y366200D01*
X1244250D01*
G01X1249675D02*
X1253550Y378700D01*
X1257425Y366200D01*
G01X1256030Y370575D02*
X1251070D01*
G01X1265950Y378700D02*
Y366200D01*
G01X1262385Y378700D02*
X1269515D01*
G01X1281450Y366200D02*
X1275250D01*
Y378700D01*
X1281450D01*
G01X1278970Y372658D02*
X1275250D01*
G01X1287340Y366200D02*
Y378700D01*
X1290440D01*
X1291680Y378075D01*
X1292610Y377242D01*
X1293385Y375992D01*
X1294005Y374533D01*
X1294160Y372450D01*
X1294005Y370367D01*
X1293385Y368908D01*
X1292610Y367658D01*
X1291680Y366825D01*
X1290440Y366200D01*
X1287340D01*
G01X1225650Y423950D02*
Y436450D01*
X1229370D01*
X1230610Y435825D01*
X1231540Y434367D01*
X1231850Y432700D01*
X1231540Y431033D01*
X1230765Y429783D01*
X1229370Y429158D01*
X1225650D01*
G01X1238050Y436450D02*
Y423950D01*
X1244250D01*
G01X1249675D02*
X1253550Y436450D01*
X1257425Y423950D01*
G01X1256030Y428325D02*
X1251070D01*
G01X1265950Y436450D02*
Y423950D01*
G01X1262385Y436450D02*
X1269515D01*
G01X1281450Y423950D02*
X1275250D01*
Y436450D01*
X1281450D01*
G01X1278970Y430408D02*
X1275250D01*
G01X1287340Y423950D02*
Y436450D01*
X1290440D01*
X1291680Y435825D01*
X1292610Y434992D01*
X1293385Y433742D01*
X1294005Y432283D01*
X1294160Y430200D01*
X1294005Y428117D01*
X1293385Y426658D01*
X1292610Y425408D01*
X1291680Y424575D01*
X1290440Y423950D01*
X1287340D01*
G01X1323300Y442700D02*
Y302200D01*
G01X1359105Y320417D02*
X1360035Y321666D01*
X1361120Y322292D01*
X1362360Y322500D01*
X1363910Y322083D01*
X1364995Y321042D01*
X1365305Y319792D01*
X1365150Y318541D01*
X1364530Y317500D01*
X1361430Y315417D01*
X1360035Y313958D01*
X1359105Y311875D01*
X1358795Y310000D01*
X1365305D01*
G01X1355850Y338100D02*
Y350600D01*
X1353990Y348100D01*
G01Y338100D02*
X1357710D01*
G01X1365305Y343308D02*
X1366390Y344767D01*
X1367320Y345600D01*
X1368560Y346017D01*
X1369645Y345600D01*
X1370420Y344767D01*
X1371040Y343517D01*
X1371195Y342058D01*
X1371040Y340808D01*
X1370420Y339558D01*
X1369490Y338517D01*
X1368405Y338100D01*
X1367165Y338517D01*
X1366080Y339766D01*
X1365460Y341642D01*
X1365305Y343725D01*
X1365615Y346433D01*
X1366080Y347892D01*
X1366855Y349350D01*
X1367940Y350392D01*
X1369025Y350600D01*
X1370110Y350183D01*
X1370885Y349142D01*
G01X1349650Y394300D02*
Y406800D01*
X1347790Y404300D01*
G01Y394300D02*
X1351510D01*
G01X1358640Y396175D02*
X1359570Y395133D01*
X1360655Y394508D01*
X1362050Y394300D01*
X1363445Y394717D01*
X1364530Y395550D01*
X1365305Y397008D01*
X1365460Y398675D01*
X1365150Y400342D01*
X1364375Y401383D01*
X1363290Y402217D01*
X1362205Y402425D01*
X1361120Y402217D01*
X1359725Y401383D01*
X1360190Y406800D01*
X1364375D01*
G01X1371505Y399508D02*
X1372590Y400967D01*
X1373520Y401800D01*
X1374760Y402217D01*
X1375845Y401800D01*
X1376620Y400967D01*
X1377240Y399717D01*
X1377395Y398258D01*
X1377240Y397008D01*
X1376620Y395758D01*
X1375690Y394717D01*
X1374605Y394300D01*
X1373365Y394717D01*
X1372280Y395966D01*
X1371660Y397842D01*
X1371505Y399925D01*
X1371815Y402633D01*
X1372280Y404092D01*
X1373055Y405550D01*
X1374140Y406592D01*
X1375225Y406800D01*
X1376310Y406383D01*
X1377085Y405342D01*
G01X1363910Y366200D02*
Y378700D01*
X1358175Y369742D01*
X1365925D01*
G01X1349650Y423950D02*
X1348410Y424158D01*
X1347325Y424991D01*
X1346395Y426242D01*
X1345775Y427700D01*
X1345465Y429367D01*
Y431033D01*
X1345775Y432700D01*
X1346395Y434158D01*
X1347325Y435408D01*
X1348410Y436242D01*
X1349650Y436450D01*
X1350890Y436242D01*
X1351975Y435408D01*
X1352905Y434158D01*
X1353525Y432700D01*
X1353835Y431033D01*
Y429367D01*
X1353525Y427700D01*
X1352905Y426242D01*
X1351975Y424991D01*
X1350890Y424158D01*
X1349650Y423950D01*
G01X1350890Y427283D02*
X1352750Y423950D01*
G01X1362050Y436450D02*
Y423950D01*
G01X1358485Y436450D02*
X1365615D01*
G01X1374450Y423950D02*
Y429575D01*
X1371350Y436450D01*
G01X1377550D02*
X1374450Y429575D01*
G01X21279Y19685D02*
G03X11201I-5039J0D01*
G01D02*
G03X21279I5039J0D01*
G01X3937Y-3937D02*
X724409D01*
G01X0Y0D02*
G03X3937Y-3937I3937J0D01*
G01X0Y35433D02*
Y0D01*
G01Y51181D02*
G03X3937Y47244I3937J0D01*
G01X0Y51181D02*
Y118898D01*
G01X4724Y47244D02*
X3937D01*
G01X29921Y63780D02*
Y47244D01*
G01X41732Y75591D02*
G03X29921Y63780I0J-11811D01*
G01X4724Y39370D02*
G03Y47244I0J3937D01*
G01X29921D02*
G03Y39370I0J-3937D01*
G01X3937D02*
G03X0Y35433I0J-3937D01*
G01X33858Y39370D02*
X3937D01*
G01X33858D02*
G03X37795Y43307I0J3937D01*
G01Y63780D02*
Y43307D01*
G01X41732Y67717D02*
G03X37795Y63780I0J-3937D01*
G01X65354Y67717D02*
X41732D01*
G01X3937Y122835D02*
G03X0Y118898I0J-3937D01*
G01X60828Y75591D02*
X41732D01*
G01X20531Y99213D02*
G03I-4291J0D01*
G01X29921Y122835D02*
X60828D01*
G01X21279Y154331D02*
G03X11201I-5039J0D01*
G01D02*
G03X21279I5039J0D01*
G01X3937Y130709D02*
X724409D01*
G01X0Y134646D02*
G03X3937Y130709I3937J0D01*
G01X0Y170079D02*
Y134646D01*
G01X4724Y122835D02*
G03Y130709I0J3937D01*
G01X29921D02*
G03Y122835I0J-3937D01*
G01X4724D02*
X3937D01*
G01X0Y185827D02*
G03X3937Y181890I3937J0D01*
G01X0Y185827D02*
Y253544D01*
G01X4724Y181890D02*
X3937D01*
G01X29921Y198426D02*
Y181890D01*
G01X41732Y210237D02*
G03X29921Y198426I0J-11811D01*
G01X60828Y210237D02*
X41732D01*
G01X4724Y174016D02*
G03Y181890I0J3937D01*
G01X29921D02*
G03Y174016I0J-3937D01*
G01X3937D02*
G03X0Y170079I0J-3937D01*
G01X33858Y174016D02*
X3937D01*
G01X33858D02*
G03X37795Y177953I0J3937D01*
G01Y198426D02*
Y177953D01*
G01X41732Y202363D02*
G03X37795Y198426I0J-3937D01*
G01X65354Y202363D02*
X41732D01*
G01X29921Y257481D02*
X60828D01*
G01X3937D02*
G03X0Y253544I0J-3937D01*
G01X4724Y257481D02*
G03Y265355I0J3937D01*
G01X29921D02*
G03Y257481I0J-3937D01*
G01X4724D02*
X3937D01*
G01X20531Y233859D02*
G03I-4291J0D01*
G01X4724Y308662D02*
G03Y316536I0J3937D01*
G01X29921D02*
G03Y308662I0J-3937D01*
G01X21279Y288977D02*
G03X11201I-5039J0D01*
G01D02*
G03X21279I5039J0D01*
G01X3937Y265355D02*
X724409D01*
G01X0Y269292D02*
G03X3937Y265355I3937J0D01*
G01X0Y304725D02*
Y269292D01*
G01X3937Y308662D02*
G03X0Y304725I0J-3937D01*
G01X33858Y308662D02*
X3937D01*
G01X33858D02*
G03X37795Y312599I0J3937D01*
G01X0Y320473D02*
G03X3937Y316536I3937J0D01*
G01X0Y320473D02*
Y388190D01*
G01X4724Y316536D02*
X3937D01*
G01X29921Y333072D02*
Y316536D01*
G01X41732Y344883D02*
G03X29921Y333072I0J-11811D01*
G01X60828Y344883D02*
X41732D01*
G01X37795Y333072D02*
Y312599D01*
G01X41732Y337009D02*
G03X37795Y333072I0J-3937D01*
G01X65354Y337009D02*
X41732D01*
G01X29921Y392127D02*
X60828D01*
G01X3937D02*
G03X0Y388190I0J-3937D01*
G01X4724Y392127D02*
G03Y400001I0J3937D01*
G01X29921D02*
G03Y392127I0J-3937D01*
G01X4724D02*
X3937D01*
G01X20531Y368505D02*
G03I-4291J0D01*
G01X3937Y400001D02*
X724409D01*
G01X0Y403938D02*
G03X3937Y400001I3937J0D01*
G01X0Y439371D02*
Y403938D01*
G01Y455119D02*
G03X3937Y451182I3937J0D01*
G01X4724D02*
X3937D01*
G01X29921Y467718D02*
Y451182D01*
G01X4724Y443308D02*
G03Y451182I0J3937D01*
G01X29921D02*
G03Y443308I0J-3937D01*
G01X21279Y423623D02*
G03X11201I-5039J0D01*
G01D02*
G03X21279I5039J0D01*
G01X3937Y443308D02*
G03X0Y439371I0J-3937D01*
G01X33858Y443308D02*
X3937D01*
G01X33858D02*
G03X37795Y447245I0J3937D01*
G01Y467718D02*
Y447245D01*
G01X0Y455119D02*
Y522836D01*
G01X41732Y479529D02*
G03X29921Y467718I0J-11811D01*
G01X60828Y479529D02*
X41732D01*
G01X20531Y503151D02*
G03I-4291J0D01*
G01X41732Y471655D02*
G03X37795Y467718I0J-3937D01*
G01X65354Y471655D02*
X41732D01*
G01X29921Y526773D02*
X60828D01*
G01X3937D02*
G03X0Y522836I0J-3937D01*
G01X4724Y526773D02*
G03Y534647I0J3937D01*
G01X29921D02*
G03Y526773I0J-3937D01*
G01X4724D02*
X3937D01*
G01Y534647D02*
X724409D01*
G01X0Y538584D02*
G03X3937Y534647I3937J0D01*
G01X0Y574017D02*
Y538584D01*
G01Y589765D02*
G03X3937Y585828I3937J0D01*
G01X0Y589765D02*
Y657482D01*
G01X4724Y585828D02*
X3937D01*
G01X29921Y602364D02*
Y585828D01*
G01X4724Y577954D02*
G03Y585828I0J3937D01*
G01X29921D02*
G03Y577954I0J-3937D01*
G01X21279Y558269D02*
G03X11201I-5039J0D01*
G01D02*
G03X21279I5039J0D01*
G01X3937Y577954D02*
G03X0Y574017I0J-3937D01*
G01X33858Y577954D02*
X3937D01*
G01X33858D02*
G03X37795Y581891I0J3937D01*
G01Y602364D02*
Y581891D01*
G01X41732Y614175D02*
G03X29921Y602364I0J-11811D01*
G01X60828Y614175D02*
X41732D01*
G01X20531Y637797D02*
G03I-4291J0D01*
G01X41732Y606301D02*
G03X37795Y602364I0J-3937D01*
G01X65354Y606301D02*
X41732D01*
G01X29921Y661419D02*
X60828D01*
G01X3937D02*
G03X0Y657482I0J-3937D01*
G01X4724Y661419D02*
G03Y669293I0J3937D01*
G01X29921D02*
G03Y661419I0J-3937D01*
G01X4724D02*
X3937D01*
G01X11201Y692915D02*
G03X21279I5039J0D01*
G01X3937Y669293D02*
X724409D01*
G01X0Y673230D02*
G03X3937Y669293I3937J0D01*
G01X0Y708663D02*
Y673230D01*
G01Y724411D02*
G03X3937Y720474I3937J0D01*
G01X0Y724411D02*
Y792128D01*
G01X4724Y720474D02*
X3937D01*
G01X29921Y737010D02*
Y720474D01*
G01X41732Y748821D02*
G03X29921Y737010I0J-11811D01*
G01X4724Y712600D02*
G03Y720474I0J3937D01*
G01X29921D02*
G03Y712600I0J-3937D01*
G01X21279Y692915D02*
G03X11201I-5039J0D01*
G01X3937Y712600D02*
G03X0Y708663I0J-3937D01*
G01X33858Y712600D02*
X3937D01*
G01X33858D02*
G03X37795Y716537I0J3937D01*
G01Y737010D02*
Y716537D01*
G01X41732Y740947D02*
G03X37795Y737010I0J-3937D01*
G01X60828Y748821D02*
X41732D01*
G01X20531Y772443D02*
G03I-4291J0D01*
G01X65354Y740947D02*
X41732D01*
G01X29921Y796065D02*
X60828D01*
G01X3937D02*
G03X0Y792128I0J-3937D01*
G01X4724Y796065D02*
G03Y803939I0J3937D01*
G01X29921D02*
G03Y796065I0J-3937D01*
G01X4724D02*
X3937D01*
G01X21279Y827561D02*
G03X11201I-5039J0D01*
G01D02*
G03X21279I5039J0D01*
G01X3937Y803939D02*
X724409D01*
G01X0Y807876D02*
G03X3937Y803939I3937J0D01*
G01X0Y843309D02*
Y807876D01*
G01Y859057D02*
G03X3937Y855120I3937J0D01*
G01X0Y859057D02*
Y922837D01*
G01X4724Y855120D02*
X3937D01*
G01X29921Y871656D02*
Y855120D01*
G01X41732Y883467D02*
G03X29921Y871656I0J-11811D01*
G01X4724Y847246D02*
G03Y855120I0J3937D01*
G01X29921D02*
G03Y847246I0J-3937D01*
G01X3937D02*
G03X0Y843309I0J-3937D01*
G01X33858Y847246D02*
X3937D01*
G01X33858D02*
G03X37795Y851183I0J3937D01*
G01Y871656D02*
Y851183D01*
G01X41732Y875593D02*
G03X37795Y871656I0J-3937D01*
G01X65354Y875593D02*
X41732D01*
G01X7874Y930711D02*
G03X0Y922837I0J-7874D01*
G01X60828Y883467D02*
X41732D01*
G01X20531Y907089D02*
G03I-4291J0D01*
G01X60828Y930711D02*
X7874D01*
G01X53445Y19685D02*
G03X42028I-5709J0D01*
G01D02*
G03X53445I5709J0D01*
G01X69291Y63780D02*
G03X65354Y67717I-3937J0D01*
G01X69291Y43307D02*
Y63780D01*
G01Y43307D02*
G03X73228Y39370I3937J0D01*
G01X156102D02*
X73228D01*
G01X64765Y118898D02*
G03X60828Y122835I-3937J0D01*
G01Y75591D02*
G03X64765Y79528I0J3937D01*
G01Y113780D02*
Y118898D01*
G01X72639Y88583D02*
G03X64765I-3937J0D01*
G01Y113780D02*
G03X72639I3937J0D01*
G01X64765Y88583D02*
Y79528D01*
G01X83879Y99213D02*
G03X93879I5000J0D01*
G01D02*
G03X83879I-5000J0D01*
G01X76576Y122835D02*
G03X72639Y118898I0J-3937D01*
G01X76576Y79528D02*
X106694D01*
G01X72639Y83465D02*
G03X76576Y79528I3937J0D01*
G01X72639Y118898D02*
Y83465D01*
G01X53445Y154331D02*
G03X42028I-5709J0D01*
G01D02*
G03X53445I5709J0D01*
G01X797048Y122835D02*
X76576D01*
G01X60828Y210237D02*
G03X64765Y214174I0J3937D01*
G01Y223229D02*
Y214174D01*
G01X76576D02*
X106694D01*
G01X72639Y218111D02*
G03X76576Y214174I3937J0D01*
G01X69291Y198426D02*
G03X65354Y202363I-3937J0D01*
G01X69291Y177953D02*
Y198426D01*
G01Y177953D02*
G03X73228Y174016I3937J0D01*
G01X156102D02*
X73228D01*
G01X64765Y253544D02*
G03X60828Y257481I-3937J0D01*
G01X64765Y248426D02*
Y253544D01*
G01X72639Y223229D02*
G03X64765I-3937J0D01*
G01Y248426D02*
G03X72639I3937J0D01*
G01X83879Y233859D02*
G03X93879I5000J0D01*
G01D02*
G03X83879I-5000J0D01*
G01X76576Y257481D02*
G03X72639Y253544I0J-3937D01*
G01X797048Y257481D02*
X76576D01*
G01X72639Y253544D02*
Y218111D01*
G01X53445Y288977D02*
G03X42028I-5709J0D01*
G01D02*
G03X53445I5709J0D01*
G01X69291Y312599D02*
G03X73228Y308662I3937J0D01*
G01X156102D02*
X73228D01*
G01X60828Y344883D02*
G03X64765Y348820I0J3937D01*
G01X72639Y357875D02*
G03X64765I-3937J0D01*
G01D02*
Y348820D01*
G01X76576D02*
X106694D01*
G01X72639Y352757D02*
G03X76576Y348820I3937J0D01*
G01X72639Y388190D02*
Y352757D01*
G01X69291Y333072D02*
G03X65354Y337009I-3937J0D01*
G01X69291Y312599D02*
Y333072D01*
G01X64765Y388190D02*
G03X60828Y392127I-3937J0D01*
G01X64765Y383072D02*
Y388190D01*
G01Y383072D02*
G03X72639I3937J0D01*
G01X83879Y368505D02*
G03X93879I5000J0D01*
G01D02*
G03X83879I-5000J0D01*
G01X76576Y392127D02*
G03X72639Y388190I0J-3937D01*
G01X797048Y392127D02*
X76576D01*
G01X53445Y423623D02*
G03X42028I-5709J0D01*
G01D02*
G03X53445I5709J0D01*
G01X69291Y447245D02*
Y467718D01*
G01Y447245D02*
G03X73228Y443308I3937J0D01*
G01X156102D02*
X73228D01*
G01X60828Y479529D02*
G03X64765Y483466I0J3937D01*
G01X72639Y492521D02*
G03X64765I-3937J0D01*
G01D02*
Y483466D01*
G01X83879Y503151D02*
G03X93879I5000J0D01*
G01X76576Y483466D02*
X106694D01*
G01X72639Y487403D02*
G03X76576Y483466I3937J0D01*
G01X72639Y522836D02*
Y487403D01*
G01X69291Y467718D02*
G03X65354Y471655I-3937J0D01*
G01X64765Y522836D02*
G03X60828Y526773I-3937J0D01*
G01X64765Y517718D02*
Y522836D01*
G01Y517718D02*
G03X72639I3937J0D01*
G01X93879Y503151D02*
G03X83879I-5000J0D01*
G01X76576Y526773D02*
G03X72639Y522836I0J-3937D01*
G01X797048Y526773D02*
X76576D01*
G01X53445Y558269D02*
G03X42028I-5709J0D01*
G01D02*
G03X53445I5709J0D01*
G01X69291Y581891D02*
Y602364D01*
G01Y581891D02*
G03X73228Y577954I3937J0D01*
G01X156102D02*
X73228D01*
G01X60828Y614175D02*
G03X64765Y618112I0J3937D01*
G01X72639Y627167D02*
G03X64765I-3937J0D01*
G01D02*
Y618112D01*
G01X83879Y637797D02*
G03X93879I5000J0D01*
G01D02*
G03X83879I-5000J0D01*
G01X76576Y618112D02*
X106694D01*
G01X72639Y622049D02*
G03X76576Y618112I3937J0D01*
G01X72639Y657482D02*
Y622049D01*
G01X69291Y602364D02*
G03X65354Y606301I-3937J0D01*
G01X64765Y657482D02*
G03X60828Y661419I-3937J0D01*
G01X64765Y652364D02*
Y657482D01*
G01Y652364D02*
G03X72639I3937J0D01*
G01X42028Y692915D02*
G03X53445I5709J0D01*
G01X76576Y661419D02*
G03X72639Y657482I0J-3937D01*
G01X797048Y661419D02*
X76576D01*
G01X53445Y692915D02*
G03X42028I-5709J0D01*
G01X69291Y737010D02*
G03X65354Y740947I-3937J0D01*
G01X69291Y716537D02*
Y737010D01*
G01Y716538D02*
G03X73228Y712601I3937J0D01*
G01X156102Y712600D02*
X73228D01*
G01X60828Y748821D02*
G03X64765Y752758I0J3937D01*
G01Y787010D02*
Y792128D01*
G01X72639Y761813D02*
G03X64765I-3937J0D01*
G01Y787010D02*
G03X72639I3937J0D01*
G01X64765Y761813D02*
Y752758D01*
G01X83879Y772443D02*
G03X93879I5000J0D01*
G01D02*
G03X83879I-5000J0D01*
G01X76576Y752758D02*
X106694D01*
G01X72639Y756695D02*
G03X76576Y752758I3937J0D01*
G01X72639Y792128D02*
Y756695D01*
G01X64765Y792128D02*
G03X60828Y796065I-3937J0D01*
G01X53445Y827561D02*
G03X42028I-5709J0D01*
G01D02*
G03X53445I5709J0D01*
G01X76576Y796065D02*
G03X72639Y792128I0J-3937D01*
G01X797048Y796065D02*
X76576D01*
G01X69291Y871656D02*
G03X65354Y875593I-3937J0D01*
G01X69291Y851183D02*
Y871656D01*
G01Y851184D02*
G03X73228Y847247I3937J0D01*
G01X156102Y847246D02*
X73228D01*
G01X60828Y883467D02*
G03X64765Y887404I0J3937D01*
G01Y926774D02*
G03X60828Y930711I-3937J0D01*
G01X64765Y921656D02*
Y926774D01*
G01X72639Y896459D02*
G03X64765I-3937J0D01*
G01Y921656D02*
G03X72639I3937J0D01*
G01X64765Y896459D02*
Y887404D01*
G01X83879Y907089D02*
G03X93879I5000J0D01*
G01D02*
G03X83879I-5000J0D01*
G01X76576Y930711D02*
G03X72639Y926774I0J-3937D01*
G01X76576Y887404D02*
X106694D01*
G01X72639Y891341D02*
G03X76576Y887404I3937J0D01*
G01X72639Y926774D02*
Y891341D01*
G01X797048Y930711D02*
X76576D01*
G01X114568Y51181D02*
X138190D01*
G01X110631Y55118D02*
G03X114568Y51181I3937J0D01*
G01X110631Y75591D02*
Y55118D01*
G01X114666Y99213D02*
G03X126083I5708J0D01*
G01D02*
G03X114666I-5709J0D01*
G01X110631Y75591D02*
G03X106694Y79528I-3937J0D01*
G01X114568Y185827D02*
X138190D01*
G01X110631Y189764D02*
G03X114568Y185827I3937J0D01*
G01X110631Y210237D02*
Y189764D01*
G01Y210237D02*
G03X106694Y214174I-3937J0D01*
G01X114666Y233859D02*
G03X126083I5708J0D01*
G01D02*
G03X114666I-5709J0D01*
G01X114568Y320473D02*
X138190D01*
G01X110631Y324410D02*
G03X114568Y320473I3937J0D01*
G01X110631Y344883D02*
Y324410D01*
G01Y344883D02*
G03X106694Y348820I-3937J0D01*
G01X114666Y368505D02*
G03X126083I5708J0D01*
G01D02*
G03X114666I-5709J0D01*
G01Y503151D02*
G03X126083I5708J0D01*
G01X114568Y455119D02*
X138190D01*
G01X110631Y459056D02*
G03X114568Y455119I3937J0D01*
G01X110631Y479529D02*
Y459056D01*
G01Y479529D02*
G03X106694Y483466I-3937J0D01*
G01X126083Y503151D02*
G03X114666I-5709J0D01*
G01X114568Y589765D02*
X138190D01*
G01X110631Y593702D02*
G03X114568Y589765I3937J0D01*
G01X110631Y614175D02*
Y593702D01*
G01X114666Y637797D02*
G03X126083I5708J0D01*
G01D02*
G03X114666I-5709J0D01*
G01X110631Y614175D02*
G03X106694Y618112I-3937J0D01*
G01X114568Y724411D02*
X138190D01*
G01X110631Y728348D02*
G03X114568Y724411I3937J0D01*
G01X110631Y748821D02*
Y728348D01*
G01X114666Y772443D02*
G03X126083I5708J0D01*
G01D02*
G03X114666I-5709J0D01*
G01X110631Y748821D02*
G03X106694Y752758I-3937J0D01*
G01X114568Y859057D02*
X138190D01*
G01X110631Y862994D02*
G03X114568Y859057I3937J0D01*
G01X110631Y883467D02*
Y862994D01*
G01X114666Y907089D02*
G03X126083I5708J0D01*
G01D02*
G03X114666I-5709J0D01*
G01X110631Y883467D02*
G03X106694Y887404I-3937J0D01*
G01X142127Y55118D02*
Y75591D01*
G01X138190Y51181D02*
G03X142127Y55118I0J3937D01*
G01X180905Y71654D02*
G03Y79528I0J3937D01*
G01X156102Y39370D02*
G03X160039Y43307I0J3937D01*
G01Y67717D02*
Y43307D01*
G01X163976Y71654D02*
G03X160039Y67717I0J-3937D01*
G01X223031Y71654D02*
X163976D01*
G01X146064Y79528D02*
X230906D01*
G01X146064D02*
G03X142127Y75591I0J-3937D01*
G01X146064Y214174D02*
X230906D01*
G01X146064D02*
G03X142127Y210237I0J-3937D01*
G01Y189764D02*
Y210237D01*
G01X138190Y185827D02*
G03X142127Y189764I0J3937D01*
G01X180905Y206300D02*
G03Y214174I0J3937D01*
G01X156102Y174016D02*
G03X160039Y177953I0J3937D01*
G01Y202363D02*
Y177953D01*
G01X163976Y206300D02*
G03X160039Y202363I0J-3937D01*
G01X223031Y206300D02*
X163976D01*
G01X156102Y308662D02*
G03X160039Y312599I0J3937D01*
G01X146064Y348820D02*
X230906D01*
G01X146064D02*
G03X142127Y344883I0J-3937D01*
G01Y324410D02*
Y344883D01*
G01X138190Y320473D02*
G03X142127Y324410I0J3937D01*
G01X180905Y340946D02*
G03Y348820I0J3937D01*
G01X160039Y337009D02*
Y312599D01*
G01X163976Y340946D02*
G03X160039Y337009I0J-3937D01*
G01X223031Y340946D02*
X163976D01*
G01X156102Y443308D02*
G03X160039Y447245I0J3937D01*
G01Y471655D02*
Y447245D01*
G01X146064Y483466D02*
X230906D01*
G01X146064D02*
G03X142127Y479529I0J-3937D01*
G01Y459056D02*
Y479529D01*
G01X138190Y455120D02*
G03X142127Y459057I0J3937D01*
G01X180905Y475592D02*
G03Y483466I0J3937D01*
G01X163976Y475592D02*
G03X160039Y471655I0J-3937D01*
G01X223031Y475592D02*
X163976D01*
G01X142127Y593702D02*
Y614175D01*
G01X138190Y589766D02*
G03X142127Y593703I0J3937D01*
G01X156102Y577954D02*
G03X160039Y581891I0J3937D01*
G01Y606301D02*
Y581891D01*
G01X146064Y618112D02*
X230906D01*
G01X146064D02*
G03X142127Y614175I0J-3937D01*
G01X180905Y610238D02*
G03Y618112I0J3937D01*
G01X163976Y610238D02*
G03X160039Y606301I0J-3937D01*
G01X223031Y610238D02*
X163976D01*
G01X142127Y728348D02*
Y748821D01*
G01X138190Y724412D02*
G03X142127Y728349I0J3937D01*
G01X156102Y712600D02*
G03X160039Y716537I0J3937D01*
G01Y740947D02*
Y716537D01*
G01X146064Y752758D02*
X230906D01*
G01X146064D02*
G03X142127Y748821I0J-3937D01*
G01X180905Y744884D02*
G03Y752758I0J3937D01*
G01X163976Y744884D02*
G03X160039Y740947I0J-3937D01*
G01X223031Y744884D02*
X163976D01*
G01X142127Y862994D02*
Y883467D01*
G01X138190Y859058D02*
G03X142127Y862995I0J3937D01*
G01X180905Y879530D02*
G03Y887404I0J3937D01*
G01X156102Y847246D02*
G03X160039Y851183I0J3937D01*
G01Y875593D02*
Y851183D01*
G01X163976Y879530D02*
G03X160039Y875593I0J-3937D01*
G01X223031Y879530D02*
X163976D01*
G01X146064Y887404D02*
X230906D01*
G01X146064D02*
G03X142127Y883467I0J-3937D01*
G01X206102Y79528D02*
G03Y71654I0J-3937D01*
G01X226969Y67717D02*
G03X223031Y71654I-3937J0D01*
G01X226969Y43307D02*
Y67717D01*
G01Y43307D02*
G03X230906Y39370I3937J0D01*
G01X282283D02*
X230906D01*
G01X234843Y75591D02*
G03X230906Y79528I-3937J0D01*
G01X196309Y122835D02*
G03Y130709I0J3937D01*
G01X221506D02*
G03Y122835I0J-3937D01*
G01X234843Y210237D02*
G03X230906Y214174I-3937J0D01*
G01X206102D02*
G03Y206300I0J-3937D01*
G01X226969Y202363D02*
G03X223031Y206300I-3937J0D01*
G01X226969Y177953D02*
Y202363D01*
G01Y177953D02*
G03X230906Y174016I3937J0D01*
G01X282283D02*
X230906D01*
G01X196309Y257481D02*
G03Y265355I0J3937D01*
G01X221506D02*
G03Y257481I0J-3937D01*
G01X226969Y312599D02*
G03X230906Y308662I3937J0D01*
G01X282283D02*
X230906D01*
G01X234843Y344883D02*
G03X230906Y348820I-3937J0D01*
G01X206102D02*
G03Y340946I0J-3937D01*
G01X226969Y337009D02*
G03X223031Y340946I-3937J0D01*
G01X226969Y312599D02*
Y337009D01*
G01X196309Y392127D02*
G03Y400001I0J3937D01*
G01X221506D02*
G03Y392127I0J-3937D01*
G01X226969Y447245D02*
Y471655D01*
G01Y447245D02*
G03X230906Y443308I3937J0D01*
G01X282283D02*
X230906D01*
G01X234843Y479529D02*
G03X230906Y483466I-3937J0D01*
G01X206102D02*
G03Y475592I0J-3937D01*
G01X226969Y471655D02*
G03X223031Y475592I-3937J0D01*
G01X196309Y526773D02*
G03Y534647I0J3937D01*
G01X221506D02*
G03Y526773I0J-3937D01*
G01X226969Y581891D02*
Y606301D01*
G01Y581891D02*
G03X230906Y577954I3937J0D01*
G01X282283D02*
X230906D01*
G01X234843Y614175D02*
G03X230906Y618112I-3937J0D01*
G01X206102D02*
G03Y610238I0J-3937D01*
G01X226969Y606301D02*
G03X223031Y610238I-3937J0D01*
G01X196309Y661419D02*
G03Y669293I0J3937D01*
G01X221506D02*
G03Y661419I0J-3937D01*
G01X226969Y716537D02*
Y740947D01*
G01Y716537D02*
G03X230906Y712600I3937J0D01*
G01X282283D02*
X230906D01*
G01X234843Y748821D02*
G03X230906Y752758I-3937J0D01*
G01X206102D02*
G03Y744884I0J-3937D01*
G01X226969Y740947D02*
G03X223031Y744884I-3937J0D01*
G01X196309Y796065D02*
G03Y803939I0J3937D01*
G01X221506D02*
G03Y796065I0J-3937D01*
G01X206102Y887404D02*
G03Y879530I0J-3937D01*
G01X226969Y875593D02*
G03X223031Y879530I-3937J0D01*
G01X226969Y851183D02*
Y875593D01*
G01Y851183D02*
G03X230906Y847246I3937J0D01*
G01X282283D02*
X230906D01*
G01X234843Y883467D02*
G03X230906Y887404I-3937J0D01*
G01X266339Y55118D02*
Y75591D01*
G01X262402Y51181D02*
G03X266339Y55118I0J3937D01*
G01X238780Y51181D02*
X262402D01*
G01X234843Y55118D02*
G03X238780Y51181I3937J0D01*
G01X234843Y75591D02*
Y55118D01*
G01X270276Y79528D02*
X355119D01*
G01X270276D02*
G03X266339Y75591I0J-3937D01*
G01X270276Y214174D02*
X355119D01*
G01X270276D02*
G03X266339Y210237I0J-3937D01*
G01Y189764D02*
Y210237D01*
G01X262402Y185827D02*
G03X266339Y189764I0J3937D01*
G01X238780Y185827D02*
X262402D01*
G01X234843Y189764D02*
G03X238780Y185827I3937J0D01*
G01X234843Y210237D02*
Y189764D01*
G01X270276Y348820D02*
X355119D01*
G01X270276D02*
G03X266339Y344883I0J-3937D01*
G01Y324410D02*
Y344883D01*
G01X262402Y320473D02*
G03X266339Y324410I0J3937D01*
G01X238780Y320473D02*
X262402D01*
G01X234843Y324410D02*
G03X238780Y320473I3937J0D01*
G01X234843Y344883D02*
Y324410D01*
G01X270276Y483466D02*
X355119D01*
G01X270276D02*
G03X266339Y479529I0J-3937D01*
G01Y459056D02*
Y479529D01*
G01X262402Y455119D02*
G03X266339Y459056I0J3937D01*
G01X238780Y455119D02*
X262402D01*
G01X234843Y459057D02*
G03X238780Y455120I3937J0D01*
G01X234843Y479529D02*
Y459056D01*
G01X266339Y593702D02*
Y614175D01*
G01X262402Y589765D02*
G03X266339Y593702I0J3937D01*
G01X238780Y589765D02*
X262402D01*
G01X234843Y593703D02*
G03X238780Y589766I3937J0D01*
G01X234843Y614175D02*
Y593702D01*
G01X270276Y618112D02*
X355119D01*
G01X270276D02*
G03X266339Y614175I0J-3937D01*
G01Y728348D02*
Y748821D01*
G01X262402Y724411D02*
G03X266339Y728348I0J3937D01*
G01X238780Y724411D02*
X262402D01*
G01X234843Y728349D02*
G03X238780Y724412I3937J0D01*
G01X234843Y748821D02*
Y728348D01*
G01X270276Y752758D02*
X355119D01*
G01X270276D02*
G03X266339Y748821I0J-3937D01*
G01Y862994D02*
Y883467D01*
G01X262402Y859057D02*
G03X266339Y862994I0J3937D01*
G01X238780Y859057D02*
X262402D01*
G01X234843Y862995D02*
G03X238780Y859058I3937J0D01*
G01X234843Y883467D02*
Y862994D01*
G01X270276Y887404D02*
X355119D01*
G01X270276D02*
G03X266339Y883467I0J-3937D01*
G01X306969Y19685D02*
G03X296969I-5000J0D01*
G01D02*
G03X306969I5000J0D01*
G01X325788Y39370D02*
G03Y47244I0J3937D01*
G01Y71654D02*
G03Y79528I0J3937D01*
G01X325591Y71654D02*
X325788D01*
G01X325591Y47244D02*
Y71654D01*
G01X325788Y47244D02*
X325591D01*
G01X282283Y39370D02*
G03X286220Y43307I0J3937D01*
G01Y63780D02*
Y43307D01*
G01X290157Y67717D02*
G03X286220Y63780I0J-3937D01*
G01X313780Y67717D02*
X290157D01*
G01X317717Y63780D02*
G03X313780Y67717I-3937J0D01*
G01X317717Y43307D02*
Y63780D01*
G01Y43307D02*
G03X321654Y39370I3937J0D01*
G01X406496D02*
X321654D01*
G01X307265Y99213D02*
G03X317343I5039J0D01*
G01D02*
G03X307265I-5039J0D01*
G01X306969Y154331D02*
G03X296969I-5000J0D01*
G01D02*
G03X306969I5000J0D01*
G01X325788Y174016D02*
G03Y181890I0J3937D01*
G01Y206300D02*
G03Y214174I0J3937D01*
G01X325591Y206300D02*
X325788D01*
G01X325591Y181890D02*
Y206300D01*
G01X325788Y181890D02*
X325591D01*
G01X282283Y174016D02*
G03X286220Y177953I0J3937D01*
G01Y198426D02*
Y177953D01*
G01X290157Y202363D02*
G03X286220Y198426I0J-3937D01*
G01X313780Y202363D02*
X290157D01*
G01X317717Y198426D02*
G03X313780Y202363I-3937J0D01*
G01X317717Y177953D02*
Y198426D01*
G01Y177953D02*
G03X321654Y174016I3937J0D01*
G01X406496D02*
X321654D01*
G01X307265Y233859D02*
G03X317343I5039J0D01*
G01D02*
G03X307265I-5039J0D01*
G01X325788Y308662D02*
G03Y316536I0J3937D01*
G01X306969Y288977D02*
G03X296969I-5000J0D01*
G01D02*
G03X306969I5000J0D01*
G01X282283Y308662D02*
G03X286220Y312599I0J3937D01*
G01X317717D02*
G03X321654Y308662I3937J0D01*
G01X406496D02*
X321654D01*
G01X325788Y340946D02*
G03Y348820I0J3937D01*
G01X325591Y340946D02*
X325788D01*
G01X325591Y316536D02*
Y340946D01*
G01X325788Y316536D02*
X325591D01*
G01X286220Y333072D02*
Y312599D01*
G01X290157Y337009D02*
G03X286220Y333072I0J-3937D01*
G01X313780Y337009D02*
X290157D01*
G01X317717Y333072D02*
G03X313780Y337009I-3937J0D01*
G01X317717Y312599D02*
Y333072D01*
G01X307265Y368505D02*
G03X317343I5039J0D01*
G01D02*
G03X307265I-5039J0D01*
G01X325788Y443308D02*
G03Y451182I0J3937D01*
G01X325591D02*
Y475592D01*
G01X325788Y451182D02*
X325591D01*
G01X306969Y423623D02*
G03X296969I-5000J0D01*
G01D02*
G03X306969I5000J0D01*
G01X282283Y443308D02*
G03X286220Y447245I0J3937D01*
G01Y467718D02*
Y447245D01*
G01X317717D02*
Y467718D01*
G01Y447245D02*
G03X321654Y443308I3937J0D01*
G01X406496D02*
X321654D01*
G01X307265Y503151D02*
G03X317343I5039J0D01*
G01X325788Y475592D02*
G03Y483466I0J3937D01*
G01X325591Y475592D02*
X325788D01*
G01X290157Y471655D02*
G03X286220Y467718I0J-3937D01*
G01X313780Y471655D02*
X290157D01*
G01X317717Y467718D02*
G03X313780Y471655I-3937J0D01*
G01X317343Y503151D02*
G03X307265I-5039J0D01*
G01X325788Y577954D02*
G03Y585828I0J3937D01*
G01X325591D02*
Y610238D01*
G01X325788Y585828D02*
X325591D01*
G01X306969Y558269D02*
G03X296969I-5000J0D01*
G01D02*
G03X306969I5000J0D01*
G01X282283Y577954D02*
G03X286220Y581891I0J3937D01*
G01Y602364D02*
Y581891D01*
G01X317717D02*
Y602364D01*
G01Y581891D02*
G03X321654Y577954I3937J0D01*
G01X406496D02*
X321654D01*
G01X307265Y637797D02*
G03X317343I5039J0D01*
G01D02*
G03X307265I-5039J0D01*
G01X325788Y610238D02*
G03Y618112I0J3937D01*
G01X325591Y610238D02*
X325788D01*
G01X290157Y606301D02*
G03X286220Y602364I0J-3937D01*
G01X313780Y606301D02*
X290157D01*
G01X317717Y602364D02*
G03X313780Y606301I-3937J0D01*
G01X296969Y692915D02*
G03X306969I5000J0D01*
G01X325788Y712600D02*
G03Y720474I0J3937D01*
G01X325591D02*
Y744884D01*
G01X325788Y720474D02*
X325591D01*
G01X306969Y692915D02*
G03X296969I-5000J0D01*
G01X282283Y712600D02*
G03X286220Y716537I0J3937D01*
G01Y737010D02*
Y716537D01*
G01X290157Y740947D02*
G03X286220Y737010I0J-3937D01*
G01X317717Y737011D02*
G03X313780Y740947I-3937J-1D01*
G01X317717Y716537D02*
Y737010D01*
G01Y716537D02*
G03X321654Y712600I3937J0D01*
G01X406496D02*
X321654D01*
G01X307265Y772443D02*
G03X317343I5039J0D01*
G01D02*
G03X307265I-5039J0D01*
G01X325788Y744884D02*
G03Y752758I0J3937D01*
G01X325591Y744884D02*
X325788D01*
G01X313780Y740947D02*
X290157D01*
G01X306969Y827561D02*
G03X296969I-5000J0D01*
G01D02*
G03X306969I5000J0D01*
G01X325788Y847246D02*
G03Y855120I0J3937D01*
G01Y879530D02*
G03Y887404I0J3937D01*
G01X325591Y879530D02*
X325788D01*
G01X325591Y855120D02*
Y879530D01*
G01X325788Y855120D02*
X325591D01*
G01X282283Y847246D02*
G03X286220Y851183I0J3937D01*
G01Y871656D02*
Y851183D01*
G01X290157Y875593D02*
G03X286220Y871656I0J-3937D01*
G01X313780Y875593D02*
X290157D01*
G01X317717Y871657D02*
G03X313780Y875593I-3937J-1D01*
G01X317717Y851183D02*
Y871656D01*
G01Y851183D02*
G03X321654Y847246I3937J0D01*
G01X406496D02*
X321654D01*
G01X307265Y907089D02*
G03X317343I5039J0D01*
G01D02*
G03X307265I-5039J0D01*
G01X362993Y51181D02*
X386615D01*
G01X359056Y55118D02*
G03X362993Y51181I3937J0D01*
G01X359056Y75591D02*
Y55118D01*
G01X350985Y71654D02*
X351182D01*
G01X350985Y47244D02*
X351182D01*
G01X350985D02*
G03Y39370I0J-3937D01*
G01Y79528D02*
G03Y71654I0J-3937D01*
G01X351182D02*
Y47244D01*
G01X359056Y75591D02*
G03X355119Y79528I-3937J0D01*
G01X362993Y185827D02*
X386615D01*
G01X359056Y189764D02*
G03X362993Y185827I3937J0D01*
G01X359056Y210237D02*
Y189764D01*
G01Y210237D02*
G03X355119Y214174I-3937J0D01*
G01X350985Y206300D02*
X351182D01*
G01X350985Y181890D02*
X351182D01*
G01X350985D02*
G03Y174016I0J-3937D01*
G01Y214174D02*
G03Y206300I0J-3937D01*
G01X351182D02*
Y181890D01*
G01X350985Y316536D02*
G03Y308662I0J-3937D01*
G01X362993Y320473D02*
X386615D01*
G01X359056Y324410D02*
G03X362993Y320473I3937J0D01*
G01X359056Y344883D02*
Y324410D01*
G01Y344883D02*
G03X355119Y348820I-3937J0D01*
G01X350985Y340946D02*
X351182D01*
G01X350985Y316536D02*
X351182D01*
G01X350985Y348820D02*
G03Y340946I0J-3937D01*
G01X351182D02*
Y316536D01*
G01X350985Y451182D02*
X351182D01*
G01X350985D02*
G03Y443308I0J-3937D01*
G01X351182Y475592D02*
Y451182D01*
G01X362993Y455119D02*
X386615D01*
G01X359056Y459056D02*
G03X362993Y455119I3937J0D01*
G01X359056Y479529D02*
Y459056D01*
G01Y479529D02*
G03X355119Y483466I-3937J0D01*
G01X350985Y475592D02*
X351182D01*
G01X350985Y483466D02*
G03Y475592I0J-3937D01*
G01X362993Y589765D02*
X386615D01*
G01X359056Y593702D02*
G03X362993Y589765I3937J0D01*
G01X359056Y614175D02*
Y593702D01*
G01X350985Y585828D02*
X351182D01*
G01X350985D02*
G03Y577954I0J-3937D01*
G01X351182Y610238D02*
Y585828D01*
G01X359056Y614175D02*
G03X355119Y618112I-3937J0D01*
G01X350985Y610238D02*
X351182D01*
G01X350985Y618112D02*
G03Y610238I0J-3937D01*
G01X362993Y724411D02*
X386615D01*
G01X359056Y728349D02*
G03X362993Y724412I3937J0D01*
G01X359056Y748821D02*
Y728348D01*
G01X350985Y720474D02*
X351182D01*
G01X350985D02*
G03Y712600I0J-3937D01*
G01X351182Y744884D02*
Y720474D01*
G01X359056Y748821D02*
G03X355119Y752758I-3937J0D01*
G01X350985Y744884D02*
X351182D01*
G01X350985Y752758D02*
G03Y744884I0J-3937D01*
G01X362993Y859057D02*
X386615D01*
G01X359056Y862995D02*
G03X362993Y859058I3937J0D01*
G01X359056Y883467D02*
Y862994D01*
G01X350985Y879530D02*
X351182D01*
G01X350985Y855120D02*
X351182D01*
G01X350985D02*
G03Y847246I0J-3937D01*
G01Y887404D02*
G03Y879530I0J-3937D01*
G01X351182D02*
Y855120D01*
G01X359056Y883467D02*
G03X355119Y887404I-3937J0D01*
G01X390552Y55118D02*
Y75591D01*
G01X386615Y51181D02*
G03X390552Y55118I0J3937D01*
G01X406496Y39370D02*
G03X410433Y43307I0J3937D01*
G01Y63780D02*
Y43307D01*
G01X414370Y67717D02*
G03X410433Y63780I0J-3937D01*
G01X437992Y67717D02*
X414370D01*
G01X394489Y79528D02*
X479331D01*
G01X394489D02*
G03X390552Y75591I0J-3937D01*
G01X387894Y122835D02*
G03Y130709I0J3937D01*
G01X413091D02*
G03Y122835I0J-3937D01*
G01X394489Y214174D02*
X479331D01*
G01X394489D02*
G03X390552Y210237I0J-3937D01*
G01Y189764D02*
Y210237D01*
G01X386615Y185827D02*
G03X390552Y189764I0J3937D01*
G01X406496Y174016D02*
G03X410433Y177953I0J3937D01*
G01Y198426D02*
Y177953D01*
G01X414370Y202363D02*
G03X410433Y198426I0J-3937D01*
G01X437992Y202363D02*
X414370D01*
G01X387894Y257481D02*
G03Y265355I0J3937D01*
G01X413091D02*
G03Y257481I0J-3937D01*
G01X406496Y308662D02*
G03X410433Y312599I0J3937D01*
G01X394489Y348820D02*
X479331D01*
G01X394489D02*
G03X390552Y344883I0J-3937D01*
G01Y324410D02*
Y344883D01*
G01X386615Y320473D02*
G03X390552Y324410I0J3937D01*
G01X410433Y333072D02*
Y312599D01*
G01X414370Y337009D02*
G03X410433Y333072I0J-3937D01*
G01X437992Y337009D02*
X414370D01*
G01X387894Y392127D02*
G03Y400001I0J3937D01*
G01X413091D02*
G03Y392127I0J-3937D01*
G01X406496Y443308D02*
G03X410433Y447245I0J3937D01*
G01Y467718D02*
Y447245D01*
G01X394489Y483466D02*
X479331D01*
G01X394489D02*
G03X390552Y479529I0J-3937D01*
G01Y459056D02*
Y479529D01*
G01X386615Y455119D02*
G03X390552Y459056I0J3937D01*
G01X414370Y471655D02*
G03X410433Y467718I0J-3937D01*
G01X437992Y471655D02*
X414370D01*
G01X387894Y526773D02*
G03Y534647I0J3937D01*
G01X413091D02*
G03Y526773I0J-3937D01*
G01X390552Y593702D02*
Y614175D01*
G01X386615Y589765D02*
G03X390552Y593702I0J3937D01*
G01X406496Y577954D02*
G03X410433Y581891I0J3937D01*
G01Y602364D02*
Y581891D01*
G01X394489Y618112D02*
X479331D01*
G01X394489D02*
G03X390552Y614175I0J-3937D01*
G01X414370Y606301D02*
G03X410433Y602364I0J-3937D01*
G01X437992Y606301D02*
X414370D01*
G01X387894Y661419D02*
G03Y669293I0J3937D01*
G01X413091D02*
G03Y661419I0J-3937D01*
G01X390552Y728348D02*
Y748821D01*
G01X386615Y724412D02*
G03X390552Y728349I0J3937D01*
G01X406496Y712600D02*
G03X410433Y716537I0J3937D01*
G01Y737010D02*
Y716537D01*
G01X414370Y740947D02*
G03X410433Y737010I0J-3937D01*
G01X394489Y752758D02*
X479331D01*
G01X394489D02*
G03X390552Y748821I0J-3937D01*
G01X437992Y740947D02*
X414370D01*
G01X387894Y796065D02*
G03Y803939I0J3937D01*
G01X413091D02*
G03Y796065I0J-3937D01*
G01X390552Y862994D02*
Y883467D01*
G01X386615Y859058D02*
G03X390552Y862995I0J3937D01*
G01X406496Y847246D02*
G03X410433Y851183I0J3937D01*
G01Y871656D02*
Y851183D01*
G01X414370Y875593D02*
G03X410433Y871656I0J-3937D01*
G01X437992Y875593D02*
X414370D01*
G01X394489Y887404D02*
X479331D01*
G01X394489D02*
G03X390552Y883467I0J-3937D01*
G01X450000Y47244D02*
X449803D01*
G01X450000Y71654D02*
X449803D01*
G01X450000D02*
G03Y79528I0J3937D01*
G01Y39370D02*
G03Y47244I0J3937D01*
G01X449803D02*
Y71654D01*
G01X441929Y63780D02*
G03X437992Y67717I-3937J0D01*
G01X441929Y43307D02*
Y63780D01*
G01Y43307D02*
G03X445866Y39370I3937J0D01*
G01X530709D02*
X445866D01*
G01X450000Y181890D02*
X449803D01*
G01X450000Y206300D02*
X449803D01*
G01X450000D02*
G03Y214174I0J3937D01*
G01Y174016D02*
G03Y181890I0J3937D01*
G01X449803D02*
Y206300D01*
G01X441929Y198426D02*
G03X437992Y202363I-3937J0D01*
G01X441929Y177953D02*
Y198426D01*
G01Y177953D02*
G03X445866Y174016I3937J0D01*
G01X530709D02*
X445866D01*
G01X450000Y308662D02*
G03Y316536I0J3937D01*
G01X441929Y312599D02*
G03X445866Y308662I3937J0D01*
G01X530709D02*
X445866D01*
G01X450000Y316536D02*
X449803D01*
G01X450000Y340946D02*
X449803D01*
G01X450000D02*
G03Y348820I0J3937D01*
G01X449803Y316536D02*
Y340946D01*
G01X441929Y333072D02*
G03X437992Y337009I-3937J0D01*
G01X441929Y312599D02*
Y333072D01*
G01X450000Y451182D02*
X449803D01*
G01X450000Y443308D02*
G03Y451182I0J3937D01*
G01X449803D02*
Y475592D01*
G01X441929Y447245D02*
Y467718D01*
G01Y447245D02*
G03X445866Y443308I3937J0D01*
G01X530709D02*
X445866D01*
G01X450000Y475592D02*
X449803D01*
G01X450000D02*
G03Y483466I0J3937D01*
G01X441929Y467718D02*
G03X437992Y471655I-3937J0D01*
G01X450000Y585828D02*
X449803D01*
G01X450000Y577954D02*
G03Y585828I0J3937D01*
G01X449803D02*
Y610238D01*
G01X441929Y581891D02*
Y602364D01*
G01Y581891D02*
G03X445866Y577954I3937J0D01*
G01X530709D02*
X445866D01*
G01X450000Y610238D02*
X449803D01*
G01X450000D02*
G03Y618112I0J3937D01*
G01X441929Y602364D02*
G03X437992Y606301I-3937J0D01*
G01X450000Y720474D02*
X449803D01*
G01X450000Y712600D02*
G03Y720474I0J3937D01*
G01X449803D02*
Y744884D01*
G01X441929Y737010D02*
G03X437992Y740947I-3937J0D01*
G01X441929Y716537D02*
Y737010D01*
G01Y716537D02*
G03X445866Y712600I3937J0D01*
G01X530709D02*
X445866D01*
G01X450000Y744884D02*
X449803D01*
G01X450000D02*
G03Y752758I0J3937D01*
G01Y855120D02*
X449803D01*
G01X450000Y879530D02*
X449803D01*
G01X450000D02*
G03Y887404I0J3937D01*
G01Y847246D02*
G03Y855120I0J3937D01*
G01X449803D02*
Y879530D01*
G01X441929Y871656D02*
G03X437992Y875593I-3937J0D01*
G01X441929Y851183D02*
Y871656D01*
G01Y851183D02*
G03X445866Y847246I3937J0D01*
G01X530709D02*
X445866D01*
G01X493720Y19685D02*
G03X483642I-5039J0D01*
G01D02*
G03X493720I5039J0D01*
G01X514765Y55118D02*
Y75591D01*
G01X510828Y51181D02*
G03X514765Y55118I0J3937D01*
G01X487205Y51181D02*
X510828D01*
G01X483269Y55118D02*
G03X487205Y51182I3937J1D01*
G01X483268Y75591D02*
Y55118D01*
G01X475197Y79528D02*
G03Y71654I0J-3937D01*
G01Y47244D02*
G03Y39370I0J-3937D01*
G01X475394Y47244D02*
X475197D01*
G01X475394Y71654D02*
Y47244D01*
G01X475197Y71654D02*
X475394D01*
G01X494017Y99213D02*
G03X504017I5000J0D01*
G01D02*
G03X494017I-5000J0D01*
G01X518702Y79528D02*
X570079D01*
G01X518702D02*
G03X514765Y75591I0J-3937D01*
G01X483268D02*
G03X479331Y79528I-3937J0D01*
G01X493720Y154331D02*
G03X483642I-5039J0D01*
G01D02*
G03X493720I5039J0D01*
G01X518702Y214174D02*
X570079D01*
G01X518702D02*
G03X514765Y210237I0J-3937D01*
G01Y189764D02*
Y210237D01*
G01X510828Y185827D02*
G03X514765Y189764I0J3937D01*
G01X487205Y185827D02*
X510828D01*
G01X483269Y189764D02*
G03X487205Y185828I3937J1D01*
G01X483268Y210237D02*
Y189764D01*
G01Y210237D02*
G03X479331Y214174I-3937J0D01*
G01X475197D02*
G03Y206300I0J-3937D01*
G01Y181890D02*
G03Y174016I0J-3937D01*
G01X475394Y181890D02*
X475197D01*
G01X475394Y206300D02*
Y181890D01*
G01X475197Y206300D02*
X475394D01*
G01X494017Y233859D02*
G03X504017I5000J0D01*
G01D02*
G03X494017I-5000J0D01*
G01X475197Y316536D02*
G03Y308662I0J-3937D01*
G01X493720Y288977D02*
G03X483642I-5039J0D01*
G01D02*
G03X493720I5039J0D01*
G01X518702Y348820D02*
X570079D01*
G01X518702D02*
G03X514765Y344883I0J-3937D01*
G01Y324410D02*
Y344883D01*
G01X510828Y320473D02*
G03X514765Y324410I0J3937D01*
G01X487205Y320473D02*
X510828D01*
G01X483269Y324410D02*
G03X487205Y320474I3937J1D01*
G01X483268Y344883D02*
Y324410D01*
G01Y344883D02*
G03X479331Y348820I-3937J0D01*
G01X475197D02*
G03Y340946I0J-3937D01*
G01X475394Y316536D02*
X475197D01*
G01X475394Y340946D02*
Y316536D01*
G01X475197Y340946D02*
X475394D01*
G01X494017Y368505D02*
G03X504017I5000J0D01*
G01D02*
G03X494017I-5000J0D01*
G01X475197Y451182D02*
G03Y443308I0J-3937D01*
G01X475394Y451182D02*
X475197D01*
G01X475394Y475592D02*
Y451182D01*
G01X493720Y423623D02*
G03X483642I-5039J0D01*
G01D02*
G03X493720I5039J0D01*
G01X494017Y503151D02*
G03X504017I5000J0D01*
G01X518702Y483466D02*
X570079D01*
G01X518702D02*
G03X514765Y479529I0J-3937D01*
G01Y459056D02*
Y479529D01*
G01X510828Y455120D02*
G03X514765Y459057I0J3937D01*
G01X487205Y455119D02*
X510828D01*
G01X483269Y459056D02*
G03X487205Y455120I3937J1D01*
G01X483268Y479529D02*
Y459056D01*
G01Y479529D02*
G03X479331Y483466I-3937J0D01*
G01X475197D02*
G03Y475592I0J-3937D01*
G01D02*
X475394D01*
G01X504017Y503151D02*
G03X494017I-5000J0D01*
G01X514765Y593702D02*
Y614175D01*
G01X510828Y589766D02*
G03X514765Y593703I0J3937D01*
G01X487205Y589765D02*
X510828D01*
G01X483269Y593702D02*
G03X487205Y589766I3937J1D01*
G01X483268Y614175D02*
Y593702D01*
G01X475197Y585828D02*
G03Y577954I0J-3937D01*
G01X475394Y585828D02*
X475197D01*
G01X475394Y610238D02*
Y585828D01*
G01X493720Y558269D02*
G03X483642I-5039J0D01*
G01D02*
G03X493720I5039J0D01*
G01X494017Y637797D02*
G03X504017I5000J0D01*
G01D02*
G03X494017I-5000J0D01*
G01X518702Y618112D02*
X570079D01*
G01X518702D02*
G03X514765Y614175I0J-3937D01*
G01X483268D02*
G03X479331Y618112I-3937J0D01*
G01X475197D02*
G03Y610238I0J-3937D01*
G01D02*
X475394D01*
G01X483642Y692915D02*
G03X493720I5039J0D01*
G01X514765Y728348D02*
Y748821D01*
G01X510828Y724412D02*
G03X514765Y728349I0J3937D01*
G01X487205Y724411D02*
X510828D01*
G01X483269Y728348D02*
G03X487205Y724412I3937J1D01*
G01X483268Y748821D02*
Y728348D01*
G01X475197Y720474D02*
G03Y712600I0J-3937D01*
G01X475394Y720474D02*
X475197D01*
G01X475394Y744884D02*
Y720474D01*
G01X493720Y692915D02*
G03X483642I-5039J0D01*
G01X494017Y772443D02*
G03X504017I5000J0D01*
G01D02*
G03X494017I-5000J0D01*
G01X518702Y752758D02*
X570079D01*
G01X518702D02*
G03X514765Y748821I0J-3937D01*
G01X483268D02*
G03X479331Y752758I-3937J0D01*
G01X475197D02*
G03Y744884I0J-3937D01*
G01D02*
X475394D01*
G01X493720Y827561D02*
G03X483642I-5039J0D01*
G01D02*
G03X493720I5039J0D01*
G01X514765Y862994D02*
Y883467D01*
G01X510828Y859058D02*
G03X514765Y862995I0J3937D01*
G01X487205Y859057D02*
X510828D01*
G01X483269Y862994D02*
G03X487205Y859058I3937J1D01*
G01X483268Y883467D02*
Y862994D01*
G01X475197Y887404D02*
G03Y879530I0J-3937D01*
G01Y855120D02*
G03Y847246I0J-3937D01*
G01X475394Y855120D02*
X475197D01*
G01X475394Y879530D02*
Y855120D01*
G01X475197Y879530D02*
X475394D01*
G01X494017Y907089D02*
G03X504017I5000J0D01*
G01D02*
G03X494017I-5000J0D01*
G01X518702Y887404D02*
X570079D01*
G01X518702D02*
G03X514765Y883467I0J-3937D01*
G01X483268D02*
G03X479331Y887404I-3937J0D01*
G01X530709Y39370D02*
G03X534646Y43307I0J3937D01*
G01Y63780D02*
Y43307D01*
G01X538583Y67717D02*
G03X534646Y63780I0J-3937D01*
G01X562205Y67717D02*
X538583D01*
G01X566142Y63780D02*
G03X562205Y67717I-3937J0D01*
G01X566142Y43307D02*
Y63780D01*
G01Y43307D02*
G03X570079Y39370I3937J0D01*
G01X530709Y174016D02*
G03X534646Y177953I0J3937D01*
G01Y198426D02*
Y177953D01*
G01X538583Y202363D02*
G03X534646Y198426I0J-3937D01*
G01X562205Y202363D02*
X538583D01*
G01X566142Y198426D02*
G03X562205Y202363I-3937J0D01*
G01X566142Y177953D02*
Y198426D01*
G01Y177953D02*
G03X570079Y174016I3937J0D01*
G01X530709Y308662D02*
G03X534646Y312599I0J3937D01*
G01Y333072D02*
Y312599D01*
G01X538583Y337009D02*
G03X534646Y333072I0J-3937D01*
G01X562205Y337009D02*
X538583D01*
G01X566142Y333072D02*
G03X562205Y337009I-3937J0D01*
G01X566142Y312599D02*
Y333072D01*
G01Y312599D02*
G03X570079Y308662I3937J0D01*
G01X530709Y443308D02*
G03X534646Y447245I0J3937D01*
G01Y467718D02*
Y447245D01*
G01X566142D02*
Y467718D01*
G01Y447245D02*
G03X570079Y443308I3937J0D01*
G01X538583Y471655D02*
G03X534646Y467718I0J-3937D01*
G01X562205Y471655D02*
X538583D01*
G01X566142Y467718D02*
G03X562205Y471655I-3937J0D01*
G01X530709Y577954D02*
G03X534646Y581891I0J3937D01*
G01Y602364D02*
Y581891D01*
G01X566142D02*
Y602364D01*
G01Y581891D02*
G03X570079Y577954I3937J0D01*
G01X538583Y606301D02*
G03X534646Y602364I0J-3937D01*
G01X562205Y606301D02*
X538583D01*
G01X566142Y602364D02*
G03X562205Y606301I-3937J0D01*
G01X530709Y712601D02*
G03X534646Y716538I0J3937D01*
G01Y737010D02*
Y716537D01*
G01X538583Y740947D02*
G03X534646Y737010I0J-3937D01*
G01X566142D02*
G03X562205Y740947I-3937J0D01*
G01X566142Y716537D02*
Y737010D01*
G01Y716537D02*
G03X570079Y712600I3937J0D01*
G01X562205Y740947D02*
X538583D01*
G01X530709Y847247D02*
G03X534646Y851184I0J3937D01*
G01Y871656D02*
Y851183D01*
G01X538583Y875593D02*
G03X534646Y871656I0J-3937D01*
G01X562205Y875593D02*
X538583D01*
G01X566142Y871656D02*
G03X562205Y875593I-3937J0D01*
G01X566142Y851183D02*
Y871656D01*
G01Y851183D02*
G03X570079Y847246I3937J0D01*
G01X577954Y47244D02*
X637009D01*
G01X574016Y51181D02*
G03X577954Y47244I3937J0D01*
G01X574016Y75591D02*
Y51181D01*
G01X594883Y39370D02*
G03Y47244I0J3937D01*
G01X654921Y39370D02*
X570079D01*
G01X574016Y75591D02*
G03X570079Y79528I-3937J0D01*
G01X604676Y130709D02*
G03Y122835I0J-3937D01*
G01X579479D02*
G03Y130709I0J3937D01*
G01X577954Y181890D02*
X637009D01*
G01X574016Y185827D02*
G03X577954Y181890I3937J0D01*
G01X574016Y210237D02*
Y185827D01*
G01Y210237D02*
G03X570079Y214174I-3937J0D01*
G01X594883Y174016D02*
G03Y181890I0J3937D01*
G01X654921Y174016D02*
X570079D01*
G01X604676Y265355D02*
G03Y257481I0J-3937D01*
G01X579479D02*
G03Y265355I0J3937D01*
G01X594883Y308662D02*
G03Y316536I0J3937D01*
G01X654921Y308662D02*
X570079D01*
G01X577954Y316536D02*
X637009D01*
G01X574016Y320473D02*
G03X577954Y316536I3937J0D01*
G01X574016Y344883D02*
Y320473D01*
G01Y344883D02*
G03X570079Y348820I-3937J0D01*
G01X604676Y400001D02*
G03Y392127I0J-3937D01*
G01X579479D02*
G03Y400001I0J3937D01*
G01X577954Y451182D02*
X637009D01*
G01X574016Y455120D02*
G03X577954Y451183I3937J0D01*
G01X594883Y443308D02*
G03Y451182I0J3937D01*
G01X654921Y443308D02*
X570079D01*
G01X574016Y479529D02*
Y455119D01*
G01Y479529D02*
G03X570079Y483466I-3937J0D01*
G01X604676Y534647D02*
G03Y526773I0J-3937D01*
G01X579479D02*
G03Y534647I0J3937D01*
G01X577954Y585828D02*
X637009D01*
G01X574016Y589766D02*
G03X577954Y585829I3937J0D01*
G01X574016Y614175D02*
Y589765D01*
G01X594883Y577954D02*
G03Y585828I0J3937D01*
G01X654921Y577954D02*
X570079D01*
G01X574016Y614175D02*
G03X570079Y618112I-3937J0D01*
G01X604676Y669293D02*
G03Y661419I0J-3937D01*
G01X579479D02*
G03Y669293I0J3937D01*
G01X577954Y720474D02*
X637009D01*
G01X574016Y724412D02*
G03X577954Y720475I3937J0D01*
G01X574016Y748821D02*
Y724411D01*
G01X594883Y712600D02*
G03Y720474I0J3937D01*
G01X654921Y712600D02*
X570079D01*
G01X574016Y748821D02*
G03X570079Y752758I-3937J0D01*
G01X604676Y803939D02*
G03Y796065I0J-3937D01*
G01X579479D02*
G03Y803939I0J3937D01*
G01X577954Y855120D02*
X637009D01*
G01X574016Y859058D02*
G03X577954Y855121I3937J0D01*
G01X574016Y883467D02*
Y859057D01*
G01X594883Y847246D02*
G03Y855120I0J3937D01*
G01X654921Y847246D02*
X570079D01*
G01X574016Y883467D02*
G03X570079Y887404I-3937J0D01*
G01X640946Y51181D02*
Y75591D01*
G01X637009Y47244D02*
G03X640946Y51181I0J3937D01*
G01X620080Y47244D02*
G03Y39370I0J-3937D01*
G01X654921D02*
G03X658858Y43307I0J3937D01*
G01Y63780D02*
Y43307D01*
G01X662795Y67717D02*
G03X658858Y63780I0J-3937D01*
G01X644883Y79528D02*
X727757D01*
G01X644883D02*
G03X640946Y75591I0J-3937D01*
G01X644883Y214174D02*
X727757D01*
G01X644883D02*
G03X640946Y210237I0J-3937D01*
G01Y185827D02*
Y210237D01*
G01X637009Y181890D02*
G03X640946Y185827I0J3937D01*
G01X620080Y181890D02*
G03Y174016I0J-3937D01*
G01X654921D02*
G03X658858Y177953I0J3937D01*
G01Y198426D02*
Y177953D01*
G01X662795Y202363D02*
G03X658858Y198426I0J-3937D01*
G01X620080Y316536D02*
G03Y308662I0J-3937D01*
G01X654921D02*
G03X658858Y312599I0J3937D01*
G01X644883Y348820D02*
X727757D01*
G01X644883D02*
G03X640946Y344883I0J-3937D01*
G01Y320473D02*
Y344883D01*
G01X637009Y316536D02*
G03X640946Y320473I0J3937D01*
G01X658858Y333072D02*
Y312599D01*
G01X662795Y337009D02*
G03X658858Y333072I0J-3937D01*
G01X637009Y451183D02*
G03X640946Y455120I0J3937D01*
G01X620080Y451182D02*
G03Y443308I0J-3937D01*
G01X654921D02*
G03X658858Y447245I0J3937D01*
G01Y467718D02*
Y447245D01*
G01X644883Y483466D02*
X727757D01*
G01X644883D02*
G03X640946Y479529I0J-3937D01*
G01Y455119D02*
Y479529D01*
G01X662795Y471655D02*
G03X658858Y467718I0J-3937D01*
G01X640946Y589765D02*
Y614175D01*
G01X637009Y585829D02*
G03X640946Y589766I0J3937D01*
G01X620080Y585828D02*
G03Y577954I0J-3937D01*
G01X654921D02*
G03X658858Y581891I0J3937D01*
G01Y602364D02*
Y581891D01*
G01X644883Y618112D02*
X727757D01*
G01X644883D02*
G03X640946Y614175I0J-3937D01*
G01X662795Y606301D02*
G03X658858Y602364I0J-3937D01*
G01X640946Y724411D02*
Y748821D01*
G01X637009Y720475D02*
G03X640946Y724412I0J3937D01*
G01X620080Y720474D02*
G03Y712600I0J-3937D01*
G01X654921D02*
G03X658858Y716537I0J3937D01*
G01Y737010D02*
Y716537D01*
G01X662795Y740947D02*
G03X658858Y737010I0J-3937D01*
G01X644883Y752758D02*
X727757D01*
G01X644883D02*
G03X640946Y748821I0J-3937D01*
G01Y859057D02*
Y883467D01*
G01X637009Y855121D02*
G03X640946Y859058I0J3937D01*
G01X620080Y855120D02*
G03Y847246I0J-3937D01*
G01X654921D02*
G03X658858Y851183I0J3937D01*
G01Y871656D02*
Y851183D01*
G01X662795Y875593D02*
G03X658858Y871656I0J-3937D01*
G01X644883Y887404D02*
X727757D01*
G01X644883D02*
G03X640946Y883467I0J-3937D01*
G01X686319Y19685D02*
G03X674902I-5708J0D01*
G01D02*
G03X686319I5708J0D01*
G01X717106D02*
G03X707106I-5000J0D01*
G01D02*
G03X717106I5000J0D01*
G01X701969Y39370D02*
G03Y47244I0J3937D01*
G01Y71654D02*
G03Y79528I0J3937D01*
G01X698228Y71654D02*
X701969D01*
G01X698228Y47244D02*
Y71654D01*
G01X701969Y47244D02*
X698228D01*
G01X686417Y67717D02*
X662795D01*
G01X690354Y63780D02*
G03X686417Y67717I-3937J0D01*
G01X690354Y43307D02*
Y63780D01*
G01Y43307D02*
G03X694291Y39370I3937J0D01*
G01X724409D02*
X694291D01*
G01X686319Y154331D02*
G03X674902I-5708J0D01*
G01D02*
G03X686319I5708J0D01*
G01X717106D02*
G03X707106I-5000J0D01*
G01D02*
G03X717106I5000J0D01*
G01X701969Y174016D02*
G03Y181890I0J3937D01*
G01Y206300D02*
G03Y214174I0J3937D01*
G01X698228Y206300D02*
X701969D01*
G01X698228Y181890D02*
Y206300D01*
G01X701969Y181890D02*
X698228D01*
G01X686417Y202363D02*
X662795D01*
G01X690354Y198426D02*
G03X686417Y202363I-3937J0D01*
G01X690354Y177953D02*
Y198426D01*
G01Y177953D02*
G03X694291Y174016I3937J0D01*
G01X724409D02*
X694291D01*
G01X701969Y308662D02*
G03Y316536I0J3937D01*
G01X686319Y288977D02*
G03X674902I-5708J0D01*
G01D02*
G03X686319I5708J0D01*
G01X717106D02*
G03X707106I-5000J0D01*
G01D02*
G03X717106I5000J0D01*
G01X690354Y312599D02*
G03X694291Y308662I3937J0D01*
G01X724409D02*
X694291D01*
G01X701969Y340946D02*
G03Y348820I0J3937D01*
G01X698228Y340946D02*
X701969D01*
G01X698228Y316536D02*
Y340946D01*
G01X701969Y316536D02*
X698228D01*
G01X686417Y337009D02*
X662795D01*
G01X690354Y333072D02*
G03X686417Y337009I-3937J0D01*
G01X690354Y312599D02*
Y333072D01*
G01X701969Y443308D02*
G03Y451182I0J3937D01*
G01X698228D02*
Y475592D01*
G01X701969Y451182D02*
X698228D01*
G01X686319Y423623D02*
G03X674902I-5708J0D01*
G01D02*
G03X686319I5708J0D01*
G01X717106D02*
G03X707106I-5000J0D01*
G01D02*
G03X717106I5000J0D01*
G01X690354Y447245D02*
Y467718D01*
G01Y447245D02*
G03X694291Y443308I3937J0D01*
G01X724409D02*
X694291D01*
G01X701969Y475592D02*
G03Y483466I0J3937D01*
G01X698228Y475592D02*
X701969D01*
G01X686417Y471655D02*
X662795D01*
G01X690354Y467718D02*
G03X686417Y471655I-3937J0D01*
G01X701969Y577954D02*
G03Y585828I0J3937D01*
G01X698228D02*
Y610238D01*
G01X701969Y585828D02*
X698228D01*
G01X686319Y558269D02*
G03X674902I-5708J0D01*
G01D02*
G03X686319I5708J0D01*
G01X717106D02*
G03X707106I-5000J0D01*
G01D02*
G03X717106I5000J0D01*
G01X690354Y581891D02*
Y602364D01*
G01Y581891D02*
G03X694291Y577954I3937J0D01*
G01X724409D02*
X694291D01*
G01X701969Y610238D02*
G03Y618112I0J3937D01*
G01X698228Y610238D02*
X701969D01*
G01X686417Y606301D02*
X662795D01*
G01X690354Y602364D02*
G03X686417Y606301I-3937J0D01*
G01X674902Y692915D02*
G03X686319I5708J0D01*
G01X707106D02*
G03X717106I5000J0D01*
G01X701969Y712600D02*
G03Y720474I0J3937D01*
G01X698228D02*
Y744884D01*
G01X701969Y720474D02*
X698228D01*
G01X686319Y692915D02*
G03X674902I-5708J0D01*
G01X717106D02*
G03X707106I-5000J0D01*
G01X690354Y737010D02*
G03X686417Y740947I-3937J0D01*
G01X690354Y716537D02*
Y737010D01*
G01Y716538D02*
G03X694291Y712601I3937J0D01*
G01X724409Y712600D02*
X694291D01*
G01X701969Y744884D02*
G03Y752758I0J3937D01*
G01X698228Y744884D02*
X701969D01*
G01X686417Y740947D02*
X662795D01*
G01X686319Y827561D02*
G03X674902I-5708J0D01*
G01D02*
G03X686319I5708J0D01*
G01X717106D02*
G03X707106I-5000J0D01*
G01D02*
G03X717106I5000J0D01*
G01X701969Y847246D02*
G03Y855120I0J3937D01*
G01Y879530D02*
G03Y887404I0J3937D01*
G01X698228Y879530D02*
X701969D01*
G01X698228Y855120D02*
Y879530D01*
G01X701969Y855120D02*
X698228D01*
G01X686417Y875593D02*
X662795D01*
G01X690354Y871656D02*
G03X686417Y875593I-3937J0D01*
G01X690354Y851183D02*
Y871656D01*
G01Y851184D02*
G03X694291Y847247I3937J0D01*
G01X724409Y847246D02*
X694291D01*
G01X736220Y0D02*
G03X740157Y-3937I3937J0D01*
G01X736220Y5118D02*
Y0D01*
G01X740157Y-3937D02*
X793111D01*
G01X736220Y5118D02*
G03X728346I-3937J0D01*
G01X724409Y-3937D02*
G03X728346Y0I0J3937D01*
G01D02*
Y35433D01*
G01X720079Y47244D02*
G03Y39370I0J-3937D01*
G01Y79528D02*
G03Y71654I0J-3937D01*
G01X723820D02*
Y47244D01*
G01X720079Y71654D02*
X723820D01*
G01Y47244D02*
X720079D01*
G01X740157Y43307D02*
G03X736220Y39370I0J-3937D01*
G01X740157Y43307D02*
X759253D01*
G01X736220Y30315D02*
Y39370D01*
G01X735631Y51181D02*
X759253D01*
G01X731694Y55118D02*
G03X735631Y51181I3937J0D01*
G01X731694Y75591D02*
Y55118D01*
G01X728346Y30315D02*
G03X736220I3937J0D01*
G01X728346Y35433D02*
G03X724409Y39370I-3937J0D01*
G01X747540Y99213D02*
G03X758957I5708J0D01*
G01D02*
G03X747540I-5709J0D01*
G01X731694Y75591D02*
G03X727757Y79528I-3937J0D01*
G01X736220Y134646D02*
G03X740157Y130709I3937J0D01*
G01X771064D02*
X740157D01*
G01X736220Y139764D02*
Y134646D01*
G01X728346Y164961D02*
G03X736220I3937J0D01*
G01Y139764D02*
G03X728346I-3937J0D01*
G01X724409Y130709D02*
G03X728346Y134646I0J3937D01*
G01X736220Y164961D02*
Y174016D01*
G01X728346Y134646D02*
Y170079D01*
G01X720079Y181890D02*
G03Y174016I0J-3937D01*
G01Y214174D02*
G03Y206300I0J-3937D01*
G01X723820D02*
Y181890D01*
G01X720079Y206300D02*
X723820D01*
G01Y181890D02*
X720079D01*
G01X740157Y177953D02*
G03X736220Y174016I0J-3937D01*
G01X740157Y177953D02*
X759253D01*
G01X735631Y185827D02*
X759253D01*
G01X731694Y189764D02*
G03X735631Y185827I3937J0D01*
G01X731694Y210237D02*
Y189764D01*
G01Y210237D02*
G03X727757Y214174I-3937J0D01*
G01X728346Y170079D02*
G03X724409Y174016I-3937J0D01*
G01X747540Y233859D02*
G03X758957I5708J0D01*
G01D02*
G03X747540I-5709J0D01*
G01X720079Y316536D02*
G03Y308662I0J-3937D01*
G01X736220Y269292D02*
G03X740157Y265355I3937J0D01*
G01Y312599D02*
G03X736220Y308662I0J-3937D01*
G01X771064Y265355D02*
X740157D01*
G01X736220Y274410D02*
Y269292D01*
G01X728346Y299607D02*
G03X736220I3937J0D01*
G01Y274410D02*
G03X728346I-3937J0D01*
G01X736220Y299607D02*
Y308662D01*
G01X724409Y265355D02*
G03X728346Y269292I0J3937D01*
G01Y304725D02*
G03X724409Y308662I-3937J0D01*
G01X728346Y269292D02*
Y304725D01*
G01X720079Y348820D02*
G03Y340946I0J-3937D01*
G01X723820D02*
Y316536D01*
G01X720079Y340946D02*
X723820D01*
G01Y316536D02*
X720079D01*
G01X740157Y312599D02*
X759253D01*
G01X735631Y320473D02*
X759253D01*
G01X731694Y324410D02*
G03X735631Y320473I3937J0D01*
G01X731694Y344883D02*
Y324410D01*
G01Y344883D02*
G03X727757Y348820I-3937J0D01*
G01X736220Y403938D02*
G03X740157Y400001I3937J0D01*
G01X771064D02*
X740157D01*
G01X736220Y409056D02*
Y403938D01*
G01X724409Y400001D02*
G03X728346Y403938I0J3937D01*
G01D02*
Y439371D01*
G01X747540Y368505D02*
G03X758957I5708J0D01*
G01D02*
G03X747540I-5709J0D01*
G01X720079Y451182D02*
G03Y443308I0J-3937D01*
G01X723820Y475592D02*
Y451182D01*
G01D02*
X720079D01*
G01X740157Y447245D02*
G03X736220Y443308I0J-3937D01*
G01X740157Y447245D02*
X759253D01*
G01X728346Y434253D02*
G03X736220I3937J0D01*
G01Y409056D02*
G03X728346I-3937J0D01*
G01X736220Y434253D02*
Y443308D01*
G01X728346Y439371D02*
G03X724409Y443308I-3937J0D01*
G01X720079Y483466D02*
G03Y475592I0J-3937D01*
G01D02*
X723820D01*
G01X747540Y503151D02*
G03X758957I5708J0D01*
G01X735631Y455119D02*
X759253D01*
G01X731694Y459056D02*
G03X735631Y455119I3937J0D01*
G01X731694Y479529D02*
Y459056D01*
G01Y479529D02*
G03X727757Y483466I-3937J0D01*
G01X736220Y538584D02*
G03X740157Y534647I3937J0D01*
G01X771064D02*
X740157D01*
G01X736220Y543702D02*
Y538584D01*
G01Y543702D02*
G03X728346I-3937J0D01*
G01X724409Y534647D02*
G03X728346Y538584I0J3937D01*
G01D02*
Y574017D01*
G01X758957Y503151D02*
G03X747540I-5709J0D01*
G01X720079Y585828D02*
G03Y577954I0J-3937D01*
G01X723820Y610238D02*
Y585828D01*
G01D02*
X720079D01*
G01X740157Y581891D02*
G03X736220Y577954I0J-3937D01*
G01X740157Y581891D02*
X759253D01*
G01X728346Y568899D02*
G03X736220I3937J0D01*
G01D02*
Y577954D01*
G01X735631Y589765D02*
X759253D01*
G01X731694Y593702D02*
G03X735631Y589765I3937J0D01*
G01X731694Y614175D02*
Y593702D01*
G01X728346Y574017D02*
G03X724409Y577954I-3937J0D01*
G01X720079Y618112D02*
G03Y610238I0J-3937D01*
G01D02*
X723820D01*
G01X747540Y637797D02*
G03X758957I5708J0D01*
G01D02*
G03X747540I-5709J0D01*
G01X731694Y614175D02*
G03X727757Y618112I-3937J0D01*
G01X736220Y673230D02*
G03X740157Y669293I3937J0D01*
G01X771064D02*
X740157D01*
G01X736220Y678348D02*
Y673230D01*
G01Y678348D02*
G03X728346I-3937J0D01*
G01X724409Y669293D02*
G03X728346Y673230I0J3937D01*
G01D02*
Y708663D01*
G01X720079Y720474D02*
G03Y712600I0J-3937D01*
G01X723820Y744884D02*
Y720474D01*
G01D02*
X720079D01*
G01X740157Y716537D02*
G03X736220Y712600I0J-3937D01*
G01X740157Y716537D02*
X759253D01*
G01X728346Y703545D02*
G03X736220I3937J0D01*
G01D02*
Y712600D01*
G01X735631Y724411D02*
X759253D01*
G01X731694Y728348D02*
G03X735631Y724411I3937J0D01*
G01X731694Y748821D02*
Y728348D01*
G01X728346Y708664D02*
G03X724409Y712601I-3937J0D01*
G01X720079Y752758D02*
G03Y744884I0J-3937D01*
G01D02*
X723820D01*
G01X747540Y772443D02*
G03X758957I5708J0D01*
G01D02*
G03X747540I-5709J0D01*
G01X731694Y748821D02*
G03X727757Y752758I-3937J0D01*
G01X736220Y807876D02*
G03X740157Y803939I3937J0D01*
G01X771064D02*
X740157D01*
G01X736220Y812995D02*
Y807876D01*
G01X728346Y838191D02*
G03X736220I3937J0D01*
G01Y812995D02*
G03X728346I-3937J0D01*
G01X724409Y803939D02*
G03X728346Y807876I0J3937D01*
G01D02*
Y843309D01*
G01X720079Y855120D02*
G03Y847246I0J-3937D01*
G01Y887404D02*
G03Y879530I0J-3937D01*
G01X723820D02*
Y855120D01*
G01X720079Y879530D02*
X723820D01*
G01Y855120D02*
X720079D01*
G01X740157Y851183D02*
G03X736220Y847246I0J-3937D01*
G01X740157Y851183D02*
X759253D01*
G01X736220Y838191D02*
Y847246D01*
G01X735631Y859057D02*
X759253D01*
G01X731694Y862994D02*
G03X735631Y859057I3937J0D01*
G01X731694Y883467D02*
Y862994D01*
G01X728346Y843310D02*
G03X724409Y847247I-3937J0D01*
G01X747540Y907089D02*
G03X758957I5708J0D01*
G01D02*
G03X747540I-5709J0D01*
G01X731694Y883467D02*
G03X727757Y887404I-3937J0D01*
G01X793111Y-3937D02*
G03X800985Y3937I0J7874D01*
G01Y67717D02*
Y3937D01*
G01X789036Y19685D02*
G03I-4291J0D01*
G01X800985Y67717D02*
G03X797048Y71654I-3937J0D01*
G01X771064Y55118D02*
Y71654D01*
G01X796261D02*
X797048D01*
G01X759253Y43307D02*
G03X771064Y55118I0J11811D01*
G01X763190D02*
Y75591D01*
G01X759253Y51181D02*
G03X763190Y55118I0J3937D01*
G01X796261Y79528D02*
G03Y71654I0J-3937D01*
G01X771064D02*
G03Y79528I0J3937D01*
G01X779706Y99213D02*
G03X789784I5039J0D01*
G01D02*
G03X779706I-5039J0D01*
G01X800985Y118898D02*
G03X797048Y122835I-3937J0D01*
G01X800985Y83465D02*
Y118898D01*
G01X797048Y79528D02*
G03X800985Y83465I0J3937D01*
G01X767127Y79528D02*
X797048D01*
G01X767127D02*
G03X763190Y75591I0J-3937D01*
G01X797048Y130709D02*
G03X800985Y134646I0J3937D01*
G01X796261Y130709D02*
X797048D01*
G01X800985Y202363D02*
Y134646D01*
G01X789036Y154331D02*
G03I-4291J0D01*
G01X771064Y122835D02*
G03Y130709I0J3937D01*
G01X796261D02*
G03Y122835I0J-3937D01*
G01X800985Y202363D02*
G03X797048Y206300I-3937J0D01*
G01Y214174D02*
G03X800985Y218111I0J3937D01*
G01X796261Y206300D02*
X797048D01*
G01X767127Y214174D02*
X797048D01*
G01X767127D02*
G03X763190Y210237I0J-3937D01*
G01X771064Y189764D02*
Y206300D01*
G01X763190Y189764D02*
Y210237D01*
G01X759253Y177953D02*
G03X771064Y189764I0J11811D01*
G01X759253Y185827D02*
G03X763190Y189764I0J3937D01*
G01X796261Y214174D02*
G03Y206300I0J-3937D01*
G01X771064D02*
G03Y214174I0J3937D01*
G01Y257481D02*
G03Y265355I0J3937D01*
G01X796261D02*
G03Y257481I0J-3937D01*
G01X779706Y233859D02*
G03X789784I5039J0D01*
G01D02*
G03X779706I-5039J0D01*
G01X800985Y253544D02*
G03X797048Y257481I-3937J0D01*
G01X800985Y218111D02*
Y253544D01*
G01X797048Y265355D02*
G03X800985Y269292I0J3937D01*
G01X796261Y265355D02*
X797048D01*
G01X800985Y337009D02*
Y269292D01*
G01X789036Y288977D02*
G03I-4291J0D01*
G01X800985Y337009D02*
G03X797048Y340946I-3937J0D01*
G01X796261D02*
X797048D01*
G01X771064Y324410D02*
Y340946D01*
G01X759253Y312599D02*
G03X771064Y324410I0J11811D01*
G01X796261Y348820D02*
G03Y340946I0J-3937D01*
G01X771064D02*
G03Y348820I0J3937D01*
G01X800985Y352757D02*
Y388190D01*
G01X797048Y348820D02*
G03X800985Y352757I0J3937D01*
G01X767127Y348820D02*
X797048D01*
G01X767127D02*
G03X763190Y344883I0J-3937D01*
G01Y324410D02*
Y344883D01*
G01X759253Y320473D02*
G03X763190Y324410I0J3937D01*
G01X797048Y400001D02*
G03X800985Y403938I0J3937D01*
G01X796261Y400001D02*
X797048D01*
G01X800985Y471655D02*
Y403938D01*
G01X771064Y392127D02*
G03Y400001I0J3937D01*
G01X796261D02*
G03Y392127I0J-3937D01*
G01X779706Y368505D02*
G03X789784I5039J0D01*
G01D02*
G03X779706I-5039J0D01*
G01X800985Y388190D02*
G03X797048Y392127I-3937J0D01*
G01X759253Y447246D02*
G03X771064Y459057I0J11811D01*
G01X789036Y423623D02*
G03I-4291J0D01*
G01X800985Y471655D02*
G03X797048Y475592I-3937J0D01*
G01X796261D02*
X797048D01*
G01X771064Y459056D02*
Y475592D01*
G01X796261Y483466D02*
G03Y475592I0J-3937D01*
G01X771064D02*
G03Y483466I0J3937D01*
G01X779706Y503151D02*
G03X789784I5039J0D01*
G01X800985Y487403D02*
Y522836D01*
G01X797048Y483466D02*
G03X800985Y487403I0J3937D01*
G01X767127Y483466D02*
X797048D01*
G01X767127D02*
G03X763190Y479529I0J-3937D01*
G01Y459056D02*
Y479529D01*
G01X759253Y455120D02*
G03X763190Y459057I0J3937D01*
G01X797048Y534647D02*
G03X800985Y538584I0J3937D01*
G01X796261Y534647D02*
X797048D01*
G01X800985Y606301D02*
Y538584D01*
G01X771064Y526773D02*
G03Y534647I0J3937D01*
G01X796261D02*
G03Y526773I0J-3937D01*
G01X789784Y503151D02*
G03X779706I-5039J0D01*
G01X800985Y522836D02*
G03X797048Y526773I-3937J0D01*
G01X771064Y593702D02*
Y610238D01*
G01X759253Y581892D02*
G03X771064Y593703I0J11811D01*
G01X789036Y558269D02*
G03I-4291J0D01*
G01X763190Y593702D02*
Y614175D01*
G01X759253Y589766D02*
G03X763190Y593703I0J3937D01*
G01X800985Y606301D02*
G03X797048Y610238I-3937J0D01*
G01X796261D02*
X797048D01*
G01X796261Y618112D02*
G03Y610238I0J-3937D01*
G01X771064D02*
G03Y618112I0J3937D01*
G01X779706Y637797D02*
G03X789784I5039J0D01*
G01D02*
G03X779706I-5039J0D01*
G01X800985Y622049D02*
Y657482D01*
G01X797048Y618112D02*
G03X800985Y622049I0J3937D01*
G01X767127Y618112D02*
X797048D01*
G01X767127D02*
G03X763190Y614175I0J-3937D01*
G01X797048Y669293D02*
G03X800985Y673230I0J3937D01*
G01X796261Y669293D02*
X797048D01*
G01X800985Y740947D02*
Y673230D01*
G01X789036Y692915D02*
G03I-4291J0D01*
G01X771064Y661419D02*
G03Y669293I0J3937D01*
G01X796261D02*
G03Y661419I0J-3937D01*
G01X800985Y657482D02*
G03X797048Y661419I-3937J0D01*
G01X771064Y728348D02*
Y744884D01*
G01X759253Y716538D02*
G03X771064Y728349I0J11811D01*
G01X763190Y728348D02*
Y748821D01*
G01X759253Y724412D02*
G03X763190Y728349I0J3937D01*
G01X800985Y740947D02*
G03X797048Y744884I-3937J0D01*
G01X796261D02*
X797048D01*
G01X796261Y752758D02*
G03Y744884I0J-3937D01*
G01X771064D02*
G03Y752758I0J3937D01*
G01X779706Y772443D02*
G03X789784I5039J0D01*
G01D02*
G03X779706I-5039J0D01*
G01X800985Y756695D02*
Y792128D01*
G01X797048Y752758D02*
G03X800985Y756695I0J3937D01*
G01X767127Y752758D02*
X797048D01*
G01X767127D02*
G03X763190Y748821I0J-3937D01*
G01X800985Y855100D02*
Y807876D01*
G01X797048Y803939D02*
G03X800985Y807876I0J3937D01*
G01X796261Y803939D02*
X797048D01*
G01X789036Y827561D02*
G03I-4291J0D01*
G01X771064Y796065D02*
G03Y803939I0J3937D01*
G01X796261D02*
G03Y796065I0J-3937D01*
G01X800985Y792128D02*
G03X797048Y796065I-3937J0D01*
G01X800985Y862974D02*
G03Y855100I0J-3937D01*
G01Y875593D02*
G03X797048Y879530I-3937J0D01*
G01X800985Y875593D02*
Y862974D01*
G01X796261Y879530D02*
X797048D01*
G01X771064Y862994D02*
Y879530D01*
G01X759253Y851184D02*
G03X771064Y862995I0J11811D01*
G01X796261Y887404D02*
G03Y879530I0J-3937D01*
G01X771064D02*
G03Y887404I0J3937D01*
G01X763190Y862994D02*
Y883467D01*
G01X759253Y859058D02*
G03X763190Y862995I0J3937D01*
G01X779706Y907089D02*
G03X789784I5039J0D01*
G01D02*
G03X779706I-5039J0D01*
G01X800985Y926774D02*
G03X797048Y930711I-3937J0D01*
G01X800985Y891341D02*
Y926774D01*
G01X797048Y887404D02*
G03X800985Y891341I0J3937D01*
G01X767127Y887404D02*
X797048D01*
G01X767127D02*
G03X763190Y883467I0J-3937D01*
M02*
